P  UNITS CUST 0
C   
C   vSure IPC 356 OUTPUT.  
C
C   FTP Site : valor.com
C   WEB Site : http://www.valor.com 
C
P   NNAME00000     ADM1276_LATCH_B                                          
P   NNAME00001     TEMP_ALM#_REVERSE_R                                      
P   NNAME00002     I2C_C_SCL_CONN_R                                         
P   NNAME00003     I2C_C_SDA_CONN_R                                         
P   NNAME00004     PWM_OUT_FAN1_NET                                         
P   NNAME00005     P12VL_2490_EN_1                                          
P   NNAME00006     P12VL_2490_EN_2                                          
P   NNAME00007     PEER_TRAY_PRESENT_LOWER                                  
P   NNAME00008     FCB_HW_REVISION                                          
P   NNAME00009     SD_LATCH_RELEASE_L                                       
P   NNAME00010     SELF_TRAY_PRESENT_LOWER                                  
P   NNAME00011     PWM_OUT_FAN2_NET                                         
P   NNAME00012     PWM_OUT_FAN3_NET                                         
P   NNAME00013     PWM_OUT_FAN4_NET                                         
P   NNAME00014     PWM_OUT_FAN5_NET                                         
P   NNAME00015     PWM_OUT_FAN6_NET                                         
P   NNAME00016     P12VU_2490_EN_1                                          
P   NNAME00017     P12VU_2490_EN_2                                          
P   NNAME00018     PEER_TRAY_PRESENT_UPPER                                  
P   NNAME00019     SD_LATCH_RELEASE_U                                       
P   NNAME00020     SELF_TRAY_PRESENT_UPPER                                  
P   NNAME00021     TEMP_ALM#_REVERSE                                        
P   NNAME00022     OTP_RETRY_DIODE                                          
P   NNAME00023     LED_DR_LED0_BLUE                                         
P   NNAME00024     LED_DR_LED1_BLUE                                         
P   NNAME00025     LED_DR_LED2_BLUE                                         
P   NNAME00026     LED_DR_LED3_BLUE                                         
P   NNAME00027     LED_DR_LED4_BLUE                                         
P   NNAME00028     LED_DR_LED5_BLUE                                         
P   NNAME00029     ADM1276_GATE_RC                                          
P   NNAME00030     P12V_SENSE_TRACE                                         
P   NNAME00031     P12VU_2490_SENSE                                         
P   NNAME00032     P12VL_2490_SENSE                                         
P   NNAME00033     P12VU_2490_TIMER                                         
P   NNAME00034     P12VL_2490_TIMER                                         
P   NNAME00035     P12VU_2490_VREF                                          
P   NNAME00036     P12VL_2490_VREF                                          
P   NNAME00037     ADM1276_GATE_RSV                                         
P   NNAME00038     ADM1276_GATE_DRV1                                        
P   NNAME00039     P12VU_2490_GATE_DRV_2                                    
P   NNAME00040     P12VL_2490_GATE_DRV_2                                    
P   NNAME00041     ADM1276_GATE_DRV0                                        
P   NNAME00042     ADM1276_GATE_DRV2                                        
P   NNAME00043     ADM1276_GATE_DRV3                                        
P   NNAME00044     P12VU_2490_GATE_DRV                                      
P   NNAME00045     P12VL_2490_GATE_DRV                                      
P   NNAME00046     ADM1276_GATE_DRV                                         
P   NNAME00047     P12VL_2490_GATE                                          
P   NNAME00048     P12VU_2490_GATE                                          
P   NNAME00049     P12VU_2490_PROG                                          
P   NNAME00050     P12VL_2490_PROG                                          
P   NNAME00051     I2C_C_SDA_ADM1276                                        
P   NNAME00052     I2C_C_SCL_ADM1276                                        
P   NNAME00053     I2C_C_SDA_NCT7904                                        
P   NNAME00054     NCT7904_CASEOPEN                                         
P   NNAME00055     I2C_C_SDA_LEDDRV                                         
P   NNAME00056     I2C_C_SCL_LEDDRV                                         
P   NNAME00057     NCT7904_VSEN_P12V_AUX                                    
P   NNAME00058     PWM_BUFFER_IN_FAN1_FAN2                                  
P   NNAME00059     PWM_BUFFER_IN_FAN3_FAN4                                  
P   NNAME00060     PWM_BUFFER_IN_FAN5_FAN6                                  
P   NNAME00061     I2C_C_SCL_NCT7904                                        
P   NNAME00062     I2C_C_SCL_EEPROM                                         
P   NNAME00063     I2C_C_SDA_EEPROM                                         
P   NNAME00064     SEB_PEER_1A_1B_HB_OUT                                    
P   NNAME00065     SEB_PEER_2A_2B_HB_OUT                                    
P   NNAME00066     LED_DR_LED6_RESERVE                                      
P   NNAME00067     LED_DR_LED7_RESERVE                                      
P   NNAME00068     NCT7904_THERMTRIP                                        
P   NNAME00069     NCT7904_PROCHOT                                          
317$NONE$                       D0040PA00X+011894Y+177882               S0      
317$NONE$                       D0040PA00X+012894Y+177882               S0      
317$NONE$                       D0040PA00X+013894Y+177882               S0      
317$NONE$                       D0040PA00X+008071Y+032941               S0      
317$NONE$                       D0040PA00X+008071Y+030941               S0      
317$NONE$                       D0040PA00X+008071Y+013941               S0      
317$NONE$                       D0040PA00X+008071Y+011941               S0      
317$NONE$                       D0040PA00X+014961Y+032941               S0      
317$NONE$                       D0040PA00X+014961Y+030941               S0      
317$NONE$                       D0040PA00X+014961Y+013941               S0      
317$NONE$                       D0040PA00X+014961Y+011941               S0      
317$NONE$                       D0040PA00X+004724Y+006811               S0      
317$NONE$                       D0040PA00X+004724Y+050134               S0      
317$NONE$                       D0040PA00X+004724Y+076118               S0      
317$NONE$                       D0040PA00X+004724Y+120732               S0      
317$NONE$                       D0040PA00X+004724Y+146717               S0      
317$NONE$                       D0040PA00X+004724Y+190039               S0      
317$NONE$                       D0040PA00X+002992Y+002480               S0      
317$NONE$                       D0040PA00X+002992Y+011142               S0      
317$NONE$                       D0040PA00X+002992Y+045803               S0      
317$NONE$                       D0040PA00X+002992Y+054465               S0      
317$NONE$                       D0040PA00X+002992Y+071787               S0      
317$NONE$                       D0040PA00X+002992Y+080449               S0      
317$NONE$                       D0040PA00X+003000Y+116400               S0      
317$NONE$                       D0040PA00X+002992Y+125063               S0      
317$NONE$                       D0040PA00X+002992Y+142386               S0      
317$NONE$                       D0040PA00X+002992Y+151047               S0      
317$NONE$                       D0040PA00X+002992Y+185709               S0      
317$NONE$                       D0040PA00X+002992Y+194370               S0      
327$NONE$                       D0040PA01X+017118Y+073230               S0      
327$NONE$                       D0040PA01X+016862Y+073230               S0      
327$NONE$                       D0040PA01X+015000Y+006450               S0      
327$NONE$                       D0040PA01X+015250Y+190600               S0      
327$NONE$                       D0040PA01X-018044Y+194726               S0      
327$NONE$                       D0040PA01X-018114Y+002001               S0      
327$NONE$                       D0040PA01X+060170Y+002125               S0      
327$NONE$                       D0040PA01X+060240Y+194850               S0      
317$NONE$                       D0040PA00X-022244Y+194882               S0      
317$NONE$                       D0040PA00X-022244Y+001969               S0      
317$NONE$                       D0040PA00X+064370Y+194882               S0      
317$NONE$                       D0040PA00X+064370Y+001969               S0      
327NCT7904_3VDD                 D0040PA01X+015227Y+060897               S0      
317NCT7904_3VDD                 D0040PA01X+014636Y+061132               S0      
317NCT7904_3VDD                 D0040PA01X+015854Y+060968               S0      
327NCT7904_3VDD                 D0040PA01X+013624Y+062244               S0      
317NCT7904_3VDD     VIA        MD0040PA01X+016310Y+060472               S0      
317GND                          D0040PA01X+016142Y+177343               S0      
317GND                          D0040PA00X+017913Y+007874               S0      
317GND                          D0040PA00X+001772Y+133858               S0      
317GND                          D0040PA00X+002756Y+181102               S0      
317GND                          D0040PA00X+017913Y+116142               S0      
317GND                          D0040PA00X+002756Y+062992               S0      
317GND                          D0040PA00X+017913Y+057087               S0      
317GND                          D0040PA00X+002756Y+015748               S0      
317GND                          D0040PA00X+017913Y+188976               S0      
317GND                          D0040PA01X+012888Y+140195               S0      
327GND                          D0040PA01X+011380Y+139714               S0      
327GND                          D0040PA01X+010640Y+140226               S0      
327GND                          D0040PA01X+018757Y+150770               S0      
327GND                          D0040PA01X+009937Y+036190               S0      
327GND                          D0040PA01X+011074Y+036180               S0      
317GND                          D0040PA00X+008071Y+023441               S0      
317GND                          D0040PA00X+008071Y+021441               S0      
317GND                          D0040PA00X+009071Y+024441               S0      
317GND                          D0040PA00X+009071Y+022441               S0      
317GND                          D0040PA00X+009071Y+020441               S0      
317GND                          D0040PA00X+008071Y+019189               S0      
317GND                          D0040PA00X+009071Y+019189               S0      
317GND                          D0040PA00X+010071Y+019189               S0      
317GND                          D0040PA00X+011071Y+019189               S0      
317GND                          D0040PA00X+008071Y+018189               S0      
317GND                          D0040PA00X+009071Y+018189               S0      
317GND                          D0040PA00X+010071Y+018189               S0      
317GND                          D0040PA00X+011071Y+018189               S0      
317GND                          D0040PA00X+008071Y+017189               S0      
317GND                          D0040PA00X+009071Y+017189               S0      
317GND                          D0040PA00X+010071Y+017189               S0      
317GND                          D0040PA00X+011071Y+017189               S0      
317GND                          D0040PA00X+008071Y+016189               S0      
317GND                          D0040PA00X+009071Y+016189               S0      
317GND                          D0040PA00X+010071Y+016189               S0      
317GND                          D0040PA00X+011071Y+016189               S0      
317GND                          D0040PA00X+014961Y+023441               S0      
317GND                          D0040PA00X+014961Y+021441               S0      
317GND                          D0040PA00X+015961Y+024441               S0      
317GND                          D0040PA00X+015961Y+022441               S0      
317GND                          D0040PA00X+015961Y+020441               S0      
317GND                          D0040PA00X+014961Y+019189               S0      
317GND                          D0040PA00X+015961Y+019189               S0      
317GND                          D0040PA00X+016961Y+019189               S0      
317GND                          D0040PA00X+017961Y+019189               S0      
317GND                          D0040PA00X+014961Y+018189               S0      
317GND                          D0040PA00X+015961Y+018189               S0      
317GND                          D0040PA00X+016961Y+018189               S0      
317GND                          D0040PA00X+017961Y+018189               S0      
317GND                          D0040PA00X+014961Y+017189               S0      
317GND                          D0040PA00X+015961Y+017189               S0      
317GND                          D0040PA00X+016961Y+017189               S0      
317GND                          D0040PA00X+017961Y+017189               S0      
317GND                          D0040PA00X+014961Y+016189               S0      
317GND                          D0040PA00X+015961Y+016189               S0      
317GND                          D0040PA00X+016961Y+016189               S0      
317GND                          D0040PA00X+017961Y+016189               S0      
317GND                          D0040PA00X+001591Y+008811               S0      
317GND                          D0040PA00X+001591Y+052134               S0      
317GND                          D0040PA00X+001591Y+078118               S0      
317GND                          D0040PA00X+001591Y+122732               S0      
317GND                          D0040PA00X+001591Y+148717               S0      
317GND                          D0040PA00X+001591Y+192039               S0      
327GND                          D0040PA01X+003236Y+168050               S0      
327GND                          D0040PA01X+011729Y+071050               S0      
327GND                          D0040PA01X+011520Y+055830               S0      
327GND                          D0040PA01X+017210Y+054150               S0      
327GND                          D0040PA01X+015227Y+060137               S0      
327GND                          D0040PA01X+017010Y+061520               S0      
327GND                          D0040PA01X+009917Y+148064               S0      
317GND                          D0040PA01X+007140Y+006815               S0      
317GND                          D0040PA01X+009120Y+144280               S0      
317GND                          D0040PA01X+007180Y+005295               S0      
317GND                          D0040PA01X+009970Y+053780               S0      
317GND                          D0040PA01X+014070Y+069550               S0      
317GND                          D0040PA01X+005810Y+103440               S0      
317GND                          D0040PA01X+007570Y+071550               S0      
317GND                          D0040PA01X+007520Y+073790               S0      
317GND                          D0040PA01X+005380Y+100950               S0      
317GND                          D0040PA01X+003500Y+058490               S0      
317GND                          D0040PA01X+006090Y+057300               S0      
317GND                          D0040PA01X+012970Y+143200               S0      
317GND                          D0040PA01X+015050Y+070280               S0      
317GND                          D0040PA01X+014636Y+060772               S0      
317GND                          D0040PA01X+016460Y+061210               S0      
317GND                          D0040PA01X+010350Y+059390               S0      
317GND                          D0040PA01X+009120Y+143490               S0      
317GND                          D0040PA01X+009120Y+143150               S0      
317GND                          D0040PA01X+006760Y+114450               S0      
317GND                          D0040PA01X+008340Y+114300               S0      
317GND                          D0040PA01X+002670Y+178780               S0      
317GND                          D0040PA01X+005180Y+176030               S0      
317GND                          D0040PA01X+010220Y+055330               S0      
317GND                          D0040PA01X+015980Y+054930               S0      
317GND                          D0040PA01X+017420Y+053640               S0      
317GND                          D0040PA01X+008740Y+057770               S0      
317GND                          D0040PA01X+014950Y+058220               S0      
317GND                          D0040PA01X+018047Y+063137               S0      
327GND                          D0040PA01X+015980Y+064584               S0      
327GND                          D0040PA01X+002763Y+164905               S0      
327GND                          D0040PA01X+015578Y+140145               S0      
327GND                          D0040PA01X+014938Y+068225               S0      
327GND                          D0040PA01X+001972Y+026255               S0      
327GND                          D0040PA01X+003268Y+030535               S0      
327GND                          D0040PA01X+005094Y+090987               S0      
327GND                          D0040PA01X+003187Y+109696               S0      
327GND                          D0040PA01X+001954Y+171487               S0      
327GND                          D0040PA01X+014644Y+142227               S0      
327GND                          D0040PA01X+017324Y+143747               S0      
317GND                          D0040PA01X+001860Y+164020               S0      
317GND                          D0040PA01X+014800Y+139400               S0      
317GND                          D0040PA01X+013470Y+140060               S0      
317GND                          D0040PA01X+008920Y+007150               S0      
317GND                          D0040PA01X+009170Y+006150               S0      
317GND                          D0040PA01X+006030Y+017930               S0      
317GND                          D0040PA01X+006030Y+016330               S0      
317GND                          D0040PA01X+005690Y+017130               S0      
317GND                          D0040PA01X+006030Y+015530               S0      
317GND                          D0040PA01X+016540Y+142680               S0      
317GND                          D0040PA01X+013150Y+094440               S0      
317GND                          D0040PA01X+013600Y+094440               S0      
317GND                          D0040PA01X+014050Y+094440               S0      
317GND                          D0040PA01X+005960Y+102060               S0      
317GND                          D0040PA01X+007700Y+073080               S0      
317GND                          D0040PA01X+007210Y+099980               S0      
317GND                          D0040PA01X+007720Y+070590               S0      
317GND                          D0040PA01X+004960Y+057350               S0      
317GND                          D0040PA01X+013354Y+066203               S0      
317GND                          D0040PA01X+016270Y+062670               S0      
317GND                          D0040PA01X+012926Y+068367               S0      
317GND                          D0040PA01X+012926Y+068806               S0      
317GND                          D0040PA01X+012936Y+069217               S0      
317GND                          D0040PA01X+009130Y+067100               S0      
317GND                          D0040PA01X+007854Y+069464               S0      
317GND                          D0040PA01X+003720Y+025690               S0      
317GND                          D0040PA01X+003920Y+034380               S0      
317GND                          D0040PA01X+002590Y+172170               S0      
317GND                          D0040PA01X+004880Y+091640               S0      
317GND                          D0040PA01X+003350Y+108360               S0      
317GND                          D0040PA01X+011253Y+095234               S0      
317GND                          D0040PA01X+011753Y+095234               S0      
317GND                          D0040PA01X+012253Y+095234               S0      
317GND                          D0040PA01X+011480Y+100130               S0      
317GND                          D0040PA01X+009560Y+142370               S0      
317GND                          D0040PA01X+010970Y+142160               S0      
317GND                          D0040PA01X+009130Y+144650               S0      
317GND                          D0040PA01X+009550Y+146420               S0      
317GND                          D0040PA01X+009350Y+147920               S0      
317GND                          D0040PA01X+014390Y+145840               S0      
317GND                          D0040PA01X+006320Y+114200               S0      
317GND                          D0040PA01X+007700Y+113450               S0      
317GND                          D0040PA01X+001990Y+176960               S0      
317GND                          D0040PA01X+005280Y+176980               S0      
317GND                          D0040PA01X+007840Y+058760               S0      
317GND                          D0040PA01X+007390Y+055880               S0      
317GND                          D0040PA01X+013668Y+055717               S0      
317GND                          D0040PA01X+009130Y+057320               S0      
317GND                          D0040PA01X+015350Y+057000               S0      
317GND                          D0040PA01X+007860Y+057450               S0      
317GND                          D0040PA01X+014530Y+058220               S0      
317GND                          D0040PA01X+012980Y+142830               S0      
317GND                          D0040PA01X+012080Y+058520               S0      
317GND                          D0040PA01X+012490Y+058520               S0      
327GND                          D0040PA01X+008944Y+064263               S0      
317GND                          D0040PA01X+016010Y+055330               S0      
317GND                          D0040PA01X+010390Y+047660               S0      
317GND                          D0040PA01X+014670Y+047670               S0      
317GND                          D0040PA01X+002890Y+069090               S0      
317GND                          D0040PA01X+006720Y+071100               S0      
317GND                          D0040PA01X+002410Y+069090               S0      
317GND                          D0040PA01X+007220Y+071100               S0      
317GND                          D0040PA01X+005060Y+025280               S0      
317GND                          D0040PA01X+006270Y+025420               S0      
317GND                          D0040PA01X+009630Y+055770               S0      
317GND                          D0040PA01X+013080Y+097580               S0      
317GND                          D0040PA01X+012990Y+099250               S0      
317GND                          D0040PA01X+015470Y+146250               S0      
317GND                          D0040PA01X+014740Y+188370               S0      
317GND                          D0040PA01X+014745Y+187870               S0      
317GND                          D0040PA01X+016330Y+069650               S0      
317GND                          D0040PA01X+007054Y+069391               S0      
317GND                          D0040PA01X+012347Y+067309               S0      
317GND                          D0040PA01X+012907Y+067309               S0      
317GND                          D0040PA01X+006564Y+069391               S0      
317GND                          D0040PA01X+010150Y+099080               S0      
317GND                          D0040PA01X+010150Y+098600               S0      
317GND                          D0040PA01X+003440Y+029430               S0      
317GND                          D0040PA01X+011130Y+038010               S0      
317GND                          D0040PA01X+018790Y+164800               S0      
317GND                          D0040PA01X+018790Y+165270               S0      
317GND                          D0040PA01X+010120Y+147450               S0      
317GND                          D0040PA01X+008920Y+145550               S0      
317GND                          D0040PA01X+005220Y+023890               S0      
317GND                          D0040PA01X+004750Y+023890               S0      
317GND                          D0040PA01X+006380Y+065760               S0      
317GND                          D0040PA01X+006380Y+066230               S0      
317GND                          D0040PA01X+010530Y+105370               S0      
317GND                          D0040PA01X+010530Y+105840               S0      
317GND                          D0040PA01X+011580Y+076410               S0      
317GND                          D0040PA01X+011580Y+076910               S0      
317GND                          D0040PA01X+014900Y+111135               S0      
317GND                          D0040PA01X+014430Y+111130               S0      
317GND                          D0040PA01X+007410Y+057620               S0      
317GND                          D0040PA01X+014040Y+057240               S0      
317GND                          D0040PA01X+008750Y+087845               S0      
317GND                          D0040PA01X+009230Y+087845               S0      
327GND                          D0040PA01X+010326Y+068492               S0      
327GND                          D0040PA01X+003625Y+068544               S0      
327GND                          D0040PA01X+005175Y+068544               S0      
327GND                          D0040PA01X+007200Y+067461               S0      
327GND                          D0040PA01X+006380Y+098660               S0      
327GND                          D0040PA01X+010600Y+138750               S0      
327GND                          D0040PA01X+015400Y+138750               S0      
327GND                          D0040PA01X+012470Y+139230               S0      
327GND                          D0040PA01X+014700Y+073200               S0      
327GND                          D0040PA01X+009600Y+093100               S0      
317GND                          D0040PA01X+007100Y+098660               S0      
317GND                          D0040PA01X+009450Y+097670               S0      
327GND                          D0040PA01X+008800Y+097630               S0      
327GND                          D0040PA01X+012164Y+096300               S0      
327GND                          D0040PA01X+015526Y+095950               S0      
327GND                          D0040PA01X+013790Y+008850               S0      
327GND                          D0040PA01X+003660Y+155150               S0      
327GND                          D0040PA01X+007890Y+149870               S0      
327GND                          D0040PA01X+007360Y+079840               S0      
327GND                          D0040PA01X+006370Y+109060               S0      
327GND                          D0040PA01X+012430Y+190830               S0      
327GND                          D0040PA01X+002290Y+039780               S0      
327GND                          D0040PA01X+018500Y+155160               S0      
327GND                          D0040PA01X+002290Y+041830               S0      
327GND                          D0040PA01X+010590Y+041900               S0      
327GND                          D0040PA01X+010590Y+039850               S0      
327GND                          D0040PA01X+018540Y+037690               S0      
327GND                          D0040PA01X+018520Y+035670               S0      
327GND                          D0040PA01X+018530Y+041840               S0      
327GND                          D0040PA01X+018530Y+039790               S0      
327GND                          D0040PA01X+018490Y+153150               S0      
327GND                          D0040PA01X+014580Y+115130               S0      
327GND                          D0040PA01X+001910Y+066700               S0      
327GND                          D0040PA01X+008020Y+147750               S0      
327GND                          D0040PA01X+019130Y+160650               S0      
327GND                          D0040PA01X+018830Y+164100               S0      
327GND                          D0040PA01X+008950Y+146930               S0      
317GND                          D0040PA01X+013350Y+147120               S0      
317GND                          D0040PA01X+005690Y+023660               S0      
317GND                          D0040PA01X+005780Y+022100               S0      
317GND                          D0040PA01X+005740Y+020790               S0      
327GND                          D0040PA01X+012660Y+145712               S0      
327GND                          D0040PA01X+011700Y+145200               S0      
327GND                          D0040PA01X+008146Y+056105               S0      
327GND                          D0040PA01X+014527Y+055925               S0      
327GND                          D0040PA01X+015838Y+071010               S0      
327GND                          D0040PA01X+017118Y+071010               S0      
327GND                          D0040PA01X+016350Y+073230               S0      
327GND                          D0040PA01X+016094Y+073230               S0      
327GND                          D0040PA01X+011617Y+084630               S0      
317GND                          D0040PA00X+016142Y+182303               S0      
317GND                          D0040PA00X+016142Y+174784               S0      
317GND                          D0040PA00X+017894Y+132874               S0      
317GND              VIA        MD0040PA04X+010400Y+073400               S0      
317GND              VIA        MD0040PA04X+012100Y+113300               S0      
317GND              VIA        MD0040PA04X+012100Y+114750               S0      
317GND              VIA        MD0040PA04X+012700Y+012900               S0      
317GND              VIA        MD0040PA04X+013170Y+057110               S0      
317GND              VIA        MD0040PA04X+014450Y+187700               S0      
317GND              VIA        MD0040PA04X+015400Y+035550               S0      
317GND              VIA        MD0040PA04X+016650Y+064000               S0      
317GND              VIA        MD0040PA04X+017100Y+140750               S0      
317GND              VIA        MD0040PA04X+017350Y+074050               S0      
317GND              VIA        MD0040PA04X+003100Y+128050               S0      
317GND              VIA        MD0040PA04X+003700Y+171400               S0      
317GND              VIA        MD0040PA04X+004200Y+065550               S0      
317GND              VIA        MD0040PA04X+005750Y+105050               S0      
317GND              VIA        MD0040PA04X+005850Y+110450               S0      
317GND              VIA        MD0040PA04X+007500Y+188200               S0      
317GND              VIA        MD0040PA04X+008800Y+103450               S0      
317GND              VIA        MD0040PA04X+009100Y+127250               S0      
317GND              VIA        MD0040PA04X+009150Y+109300               S0      
317GND              VIA        MD0040PA04X+009300Y+188450               S0      
317GND              VIA        MD0040PA04X+009750Y+190100               S0      
317GND              VIA        MD0040PA01X+012850Y+107680               S0      
317GND              VIA        MD0040PA01X+016050Y+091650               S0      
317GND              VIA        MD0040PA01X+016200Y+102700               S0      
317GND              VIA        MD0040PA01X+001860Y+024910               S0      
317GND              VIA        MD0040PA01X+003300Y+157500               S0      
317GND              VIA        MD0040PA01X+004310Y+086610               S0      
317GND              VIA        MD0040PA01X+004390Y+013720               S0      
317GND              VIA        MD0040PA00X+010086Y+140226               S0      
317GND              VIA        MD0040PA00X+010100Y+058300               S0      
317GND              VIA        MD0040PA00X+010270Y+054100               S0      
317GND              VIA        MD0040PA00X+010400Y+104950               S0      
317GND              VIA        MD0040PA00X+010400Y+106250               S0      
317GND              VIA        MD0040PA00X+010460Y+192340               S0      
317GND              VIA        MD0040PA00X+010500Y+118100               S0      
317GND              VIA        MD0040PA00X+010550Y+070250               S0      
317GND              VIA        MD0040PA00X+010600Y+070900               S0      
317GND              VIA        MD0040PA00X+010630Y+055320               S0      
317GND              VIA        MD0040PA00X+010810Y+047765               S0      
317GND              VIA        MD0040PA00X+010890Y+054130               S0      
317GND              VIA        MD0040PA00X+011100Y+139400               S0      
317GND              VIA        MD0040PA00X+011350Y+072100               S0      
317GND              VIA        MD0040PA00X+011350Y+072900               S0      
317GND              VIA        MD0040PA00X+011350Y+073600               S0      
317GND              VIA        MD0040PA00X+011350Y+074700               S0      
317GND              VIA        MD0040PA00X+011350Y+075600               S0      
317GND              VIA        MD0040PA00X+011450Y+070050               S0      
317GND              VIA        MD0040PA00X+011870Y+084070               S0      
317GND              VIA        MD0040PA00X+011950Y+073950               S0      
317GND              VIA        MD0040PA00X+011950Y+074650               S0      
317GND              VIA        MD0040PA00X+011950Y+075750               S0      
317GND              VIA        MD0040PA00X+011980Y+056830               S0      
317GND              VIA        MD0040PA00X+012100Y+058150               S0      
317GND              VIA        MD0040PA00X+012250Y+070050               S0      
317GND              VIA        MD0040PA00X+012420Y+056840               S0      
317GND              VIA        MD0040PA00X+012490Y+058200               S0      
317GND              VIA        MD0040PA00X+012500Y+139850               S0      
317GND              VIA        MD0040PA00X+012510Y+140250               S0      
317GND              VIA        MD0040PA00X+012540Y+098360               S0      
317GND              VIA        MD0040PA00X+012540Y+099200               S0      
317GND              VIA        MD0040PA00X+012890Y+192330               S0      
317GND              VIA        MD0040PA00X+013000Y+070050               S0      
317GND              VIA        MD0040PA00X+013000Y+074600               S0      
317GND              VIA        MD0040PA00X+013000Y+075300               S0      
317GND              VIA        MD0040PA00X+013000Y+076400               S0      
317GND              VIA        MD0040PA00X+013350Y+190650               S0      
317GND              VIA        MD0040PA00X+013350Y+057550               S0      
317GND              VIA        MD0040PA00X+013350Y+058200               S0      
317GND              VIA        MD0040PA00X+013460Y+058670               S0      
317GND              VIA        MD0040PA00X+013460Y+066560               S0      
317GND              VIA        MD0040PA00X+013500Y+056150               S0      
317GND              VIA        MD0040PA00X+013700Y+058990               S0      
317GND              VIA        MD0040PA00X+001400Y+047600               S0      
317GND              VIA        MD0040PA00X+014200Y+047850               S0      
317GND              VIA        MD0040PA00X+014210Y+058140               S0      
317GND              VIA        MD0040PA00X+014240Y+192380               S0      
317GND              VIA        MD0040PA00X+014250Y+055000               S0      
317GND              VIA        MD0040PA00X+014580Y+059440               S0      
317GND              VIA        MD0040PA00X+014600Y+072600               S0      
317GND              VIA        MD0040PA00X+014600Y+073800               S0      
317GND              VIA        MD0040PA00X+014600Y+075500               S0      
317GND              VIA        MD0040PA00X+014600Y+076550               S0      
317GND              VIA        MD0040PA00X+014600Y+078250               S0      
317GND              VIA        MD0040PA00X+014600Y+079650               S0      
317GND              VIA        MD0040PA00X+014600Y+082400               S0      
317GND              VIA        MD0040PA00X+014630Y+191370               S0      
317GND              VIA        MD0040PA00X+014650Y+139710               S0      
317GND              VIA        MD0040PA00X+014650Y+081200               S0      
317GND              VIA        MD0040PA00X+014700Y+052990               S0      
317GND              VIA        MD0040PA00X+014700Y+070300               S0      
317GND              VIA        MD0040PA00X+014900Y+067700               S0      
317GND              VIA        MD0040PA00X+014950Y+005200               S0      
317GND              VIA        MD0040PA00X+014980Y+100870               S0      
317GND              VIA        MD0040PA00X+015150Y+103050               S0      
317GND              VIA        MD0040PA00X+015190Y+189140               S0      
317GND              VIA        MD0040PA00X+015250Y+188310               S0      
317GND              VIA        MD0040PA00X+015350Y+103350               S0      
317GND              VIA        MD0040PA00X+015550Y+103000               S0      
317GND              VIA        MD0040PA00X+015590Y+139710               S0      
317GND              VIA        MD0040PA00X+015630Y+055210               S0      
317GND              VIA        MD0040PA00X+015750Y+066450               S0      
317GND              VIA        MD0040PA00X+015790Y+192310               S0      
317GND              VIA        MD0040PA00X+015950Y+106200               S0      
317GND              VIA        MD0040PA00X+016100Y+067400               S0      
317GND              VIA        MD0040PA00X+016150Y+074750               S0      
317GND              VIA        MD0040PA00X+016150Y+075900               S0      
317GND              VIA        MD0040PA00X+016150Y+076800               S0      
317GND              VIA        MD0040PA00X+016150Y+077800               S0      
317GND              VIA        MD0040PA00X+016160Y+073980               S0      
317GND              VIA        MD0040PA00X+016200Y+081750               S0      
317GND              VIA        MD0040PA00X+016210Y+191200               S0      
317GND              VIA        MD0040PA00X+016300Y+104250               S0      
317GND              VIA        MD0040PA00X+016310Y+097860               S0      
317GND              VIA        MD0040PA00X+016320Y+098520               S0      
317GND              VIA        MD0040PA00X+016543Y+069237               S0      
317GND              VIA        MD0040PA00X+016590Y+071730               S0      
317GND              VIA        MD0040PA00X+016600Y+075150               S0      
317GND              VIA        MD0040PA00X+016600Y+076000               S0      
317GND              VIA        MD0040PA00X+016650Y+077550               S0      
317GND              VIA        MD0040PA00X+016800Y+083000               S0      
317GND              VIA        MD0040PA00X+016900Y+142675               S0      
317GND              VIA        MD0040PA00X+017000Y+192050               S0      
317GND              VIA        MD0040PA00X+017000Y+074550               S0      
317GND              VIA        MD0040PA00X+017400Y+083450               S0      
317GND              VIA        MD0040PA00X+017510Y+071000               S0      
317GND              VIA        MD0040PA00X+017670Y+192390               S0      
317GND              VIA        MD0040PA00X+017770Y+191280               S0      
317GND              VIA        MD0040PA00X+017900Y+100500               S0      
317GND              VIA        MD0040PA00X+017950Y+088400               S0      
317GND              VIA        MD0040PA00X+017980Y+094140               S0      
317GND              VIA        MD0040PA00X+017990Y+090090               S0      
317GND              VIA        MD0040PA00X+017990Y+092570               S0      
317GND              VIA        MD0040PA00X+018000Y+085600               S0      
317GND              VIA        MD0040PA00X+018000Y+087250               S0      
317GND              VIA        MD0040PA00X+018000Y+091250               S0      
317GND              VIA        MD0040PA00X+018000Y+096040               S0      
317GND              VIA        MD0040PA00X+018050Y+097320               S0      
317GND              VIA        MD0040PA00X+018450Y+192050               S0      
317GND              VIA        MD0040PA00X+018750Y+155950               S0      
317GND              VIA        MD0040PA00X+019170Y+165270               S0      
317GND              VIA        MD0040PA00X+019250Y+164800               S0      
317GND              VIA        MD0040PA00X+019265Y+164150               S0      
317GND              VIA        MD0040PA00X+001954Y+171052               S0      
317GND              VIA        MD0040PA00X+019500Y+111200               S0      
317GND              VIA        MD0040PA00X+019650Y+160650               S0      
317GND              VIA        MD0040PA00X+020050Y+187650               S0      
317GND              VIA        MD0040PA00X+020070Y+134850               S0      
317GND              VIA        MD0040PA00X+020110Y+190880               S0      
317GND              VIA        MD0040PA00X+020120Y+189050               S0      
317GND              VIA        MD0040PA00X+020139Y+106700               S0      
317GND              VIA        MD0040PA00X+020139Y+142550               S0      
317GND              VIA        MD0040PA00X+020139Y+079700               S0      
317GND              VIA        MD0040PA00X+020150Y+101900               S0      
317GND              VIA        MD0040PA00X+020150Y+108250               S0      
317GND              VIA        MD0040PA00X+020150Y+114700               S0      
317GND              VIA        MD0040PA00X+020150Y+131000               S0      
317GND              VIA        MD0040PA00X+020150Y+135950               S0      
317GND              VIA        MD0040PA00X+020150Y+141300               S0      
317GND              VIA        MD0040PA00X+020150Y+156900               S0      
317GND              VIA        MD0040PA00X+020150Y+016500               S0      
317GND              VIA        MD0040PA00X+020150Y+069150               S0      
317GND              VIA        MD0040PA00X+020150Y+072650               S0      
317GND              VIA        MD0040PA00X+020150Y+077700               S0      
317GND              VIA        MD0040PA00X+020150Y+093150               S0      
317GND              VIA        MD0040PA00X+020150Y+099100               S0      
317GND              VIA        MD0040PA00X+020170Y+138830               S0      
317GND              VIA        MD0040PA00X+020200Y+103700               S0      
317GND              VIA        MD0040PA00X+020200Y+105200               S0      
317GND              VIA        MD0040PA00X+020200Y+121200               S0      
317GND              VIA        MD0040PA00X+020200Y+124600               S0      
317GND              VIA        MD0040PA00X+020200Y+153750               S0      
317GND              VIA        MD0040PA00X+020200Y+085950               S0      
317GND              VIA        MD0040PA00X+020200Y+087500               S0      
317GND              VIA        MD0040PA00X+020200Y+089000               S0      
317GND              VIA        MD0040PA00X+020200Y+091800               S0      
317GND              VIA        MD0040PA00X+020221Y+146200               S0      
317GND              VIA        MD0040PA00X+020221Y+155400               S0      
317GND              VIA        MD0040PA00X+020221Y+063850               S0      
317GND              VIA        MD0040PA00X+020221Y+090350               S0      
317GND              VIA        MD0040PA00X+020240Y+144400               S0      
317GND              VIA        MD0040PA00X+020250Y+100600               S0      
317GND              VIA        MD0040PA00X+020250Y+117900               S0      
317GND              VIA        MD0040PA00X+020250Y+128000               S0      
317GND              VIA        MD0040PA00X+020250Y+066600               S0      
317GND              VIA        MD0040PA00X+020250Y+075550               S0      
317GND              VIA        MD0040PA00X+020250Y+082200               S0      
317GND              VIA        MD0040PA00X+020250Y+084650               S0      
317GND              VIA        MD0040PA00X+020250Y+094550               S0      
317GND              VIA        MD0040PA00X+020250Y+096200               S0      
317GND              VIA        MD0040PA00X+020250Y+097750               S0      
317GND              VIA        MD0040PA00X+002310Y+034240               S0      
317GND              VIA        MD0040PA00X+002340Y+035350               S0      
317GND              VIA        MD0040PA00X+002670Y+152980               S0      
317GND              VIA        MD0040PA00X+002675Y+179110               S0      
317GND              VIA        MD0040PA00X+002740Y+189940               S0      
317GND              VIA        MD0040PA00X+002800Y+159680               S0      
317GND              VIA        MD0040PA00X+002880Y+053370               S0      
317GND              VIA        MD0040PA00X+002910Y+172155               S0      
317GND              VIA        MD0040PA00X+002950Y+034350               S0      
317GND              VIA        MD0040PA00X+002950Y+041050               S0      
317GND              VIA        MD0040PA00X+002950Y+058650               S0      
317GND              VIA        MD0040PA00X+003140Y+164820               S0      
317GND              VIA        MD0040PA00X+003260Y+029050               S0      
317GND              VIA        MD0040PA00X+003268Y+029950               S0      
317GND              VIA        MD0040PA00X+003320Y+046890               S0      
317GND              VIA        MD0040PA00X+003400Y+169150               S0      
317GND              VIA        MD0040PA00X+003400Y+044800               S0      
317GND              VIA        MD0040PA00X+003420Y+028480               S0      
317GND              VIA        MD0040PA00X+003550Y+167050               S0      
317GND              VIA        MD0040PA00X+003600Y+026039               S0      
317GND              VIA        MD0040PA00X+003640Y+152340               S0      
317GND              VIA        MD0040PA00X+003840Y+159670               S0      
317GND              VIA        MD0040PA00X+003870Y+189380               S0      
317GND              VIA        MD0040PA00X+003930Y+018110               S0      
317GND              VIA        MD0040PA00X+003940Y+138130               S0      
317GND              VIA        MD0040PA00X+003980Y+068140               S0      
317GND              VIA        MD0040PA00X+004030Y+170390               S0      
317GND              VIA        MD0040PA00X+004150Y+169200               S0      
317GND              VIA        MD0040PA00X+004150Y+188950               S0      
317GND              VIA        MD0040PA00X+004250Y+167300               S0      
317GND              VIA        MD0040PA00X+004250Y+026020               S0      
317GND              VIA        MD0040PA00X+004270Y+160600               S0      
317GND              VIA        MD0040PA00X+004330Y+164660               S0      
317GND              VIA        MD0040PA00X+004350Y+162070               S0      
317GND              VIA        MD0040PA00X+004360Y+166830               S0      
317GND              VIA        MD0040PA00X+004410Y+168520               S0      
317GND              VIA        MD0040PA00X+004450Y+138050               S0      
317GND              VIA        MD0040PA00X+004450Y+167800               S0      
317GND              VIA        MD0040PA00X+000459Y+071400               S0      
317GND              VIA        MD0040PA00X+000459Y+074900               S0      
317GND              VIA        MD0040PA00X+004500Y+142800               S0      
317GND              VIA        MD0040PA00X+004550Y+140000               S0      
317GND              VIA        MD0040PA00X+004550Y+169000               S0      
317GND              VIA        MD0040PA00X+004700Y+188620               S0      
317GND              VIA        MD0040PA00X+004970Y+056890               S0      
317GND              VIA        MD0040PA00X+000509Y+135450               S0      
317GND              VIA        MD0040PA00X+000509Y+057450               S0      
317GND              VIA        MD0040PA00X+005080Y+026640               S0      
317GND              VIA        MD0040PA00X+005100Y+052950               S0      
317GND              VIA        MD0040PA00X+005170Y+023480               S0      
317GND              VIA        MD0040PA00X+005250Y+175600               S0      
317GND              VIA        MD0040PA00X+005250Y+024850               S0      
317GND              VIA        MD0040PA00X+005250Y+068250               S0      
317GND              VIA        MD0040PA00X+000530Y+052890               S0      
317GND              VIA        MD0040PA00X+000530Y+054880               S0      
317GND              VIA        MD0040PA00X+005300Y+017150               S0      
317GND              VIA        MD0040PA00X+005300Y+069510               S0      
317GND              VIA        MD0040PA00X+005380Y+100620               S0      
317GND              VIA        MD0040PA00X+005420Y+020785               S0      
317GND              VIA        MD0040PA00X+005420Y+022070               S0      
317GND              VIA        MD0040PA00X+005430Y+091550               S0      
317GND              VIA        MD0040PA00X+005450Y+103550               S0      
317GND              VIA        MD0040PA00X+005460Y+057340               S0      
317GND              VIA        MD0040PA00X+005590Y+188150               S0      
317GND              VIA        MD0040PA00X+005600Y+102150               S0      
317GND              VIA        MD0040PA00X+005750Y+089030               S0      
317GND              VIA        MD0040PA00X+005750Y+098430               S0      
317GND              VIA        MD0040PA00X+005750Y+098780               S0      
317GND              VIA        MD0040PA00X+005790Y+189980               S0      
317GND              VIA        MD0040PA00X+005894Y+025629               S0      
317GND              VIA        MD0040PA00X+005950Y+088160               S0      
317GND              VIA        MD0040PA00X+005960Y+012580               S0      
317GND              VIA        MD0040PA00X+006030Y+189230               S0      
317GND              VIA        MD0040PA00X+006035Y+015195               S0      
317GND              VIA        MD0040PA00X+006200Y+187700               S0      
317GND              VIA        MD0040PA00X+006350Y+017930               S0      
317GND              VIA        MD0040PA00X+006400Y+066660               S0      
317GND              VIA        MD0040PA00X+006450Y+109900               S0      
317GND              VIA        MD0040PA00X+006500Y+016630               S0      
317GND              VIA        MD0040PA00X+006500Y+056150               S0      
317GND              VIA        MD0040PA00X+006530Y+188660               S0      
317GND              VIA        MD0040PA00X+006600Y+055050               S0      
317GND              VIA        MD0040PA00X+006620Y+065350               S0      
317GND              VIA        MD0040PA00X+007035Y+055885               S0      
317GND              VIA        MD0040PA00X+007080Y+099050               S0      
317GND              VIA        MD0040PA00X+007145Y+053219               S0      
317GND              VIA        MD0040PA00X+007150Y+073550               S0      
317GND              VIA        MD0040PA00X+007240Y+052830               S0      
317GND              VIA        MD0040PA00X+007350Y+073200               S0      
317GND              VIA        MD0040PA00X+007400Y+006050               S0      
317GND              VIA        MD0040PA00X+007500Y+006750               S0      
317GND              VIA        MD0040PA00X+007840Y+058370               S0      
317GND              VIA        MD0040PA00X+007849Y+069783               S0      
317GND              VIA        MD0040PA00X+007900Y+006550               S0      
317GND              VIA        MD0040PA00X+007990Y+192300               S0      
317GND              VIA        MD0040PA00X+008000Y+147200               S0      
317GND              VIA        MD0040PA00X+008200Y+065200               S0      
317GND              VIA        MD0040PA00X+008300Y+097980               S0      
317GND              VIA        MD0040PA00X+008320Y+145550               S0      
317GND              VIA        MD0040PA00X+008350Y+097280               S0      
317GND              VIA        MD0040PA00X+008350Y+097630               S0      
317GND              VIA        MD0040PA00X+008420Y+064387               S0      
317GND              VIA        MD0040PA00X+008450Y+005650               S0      
317GND              VIA        MD0040PA00X+008700Y+059100               S0      
317GND              VIA        MD0040PA00X+008700Y+064800               S0      
317GND              VIA        MD0040PA00X+008800Y+058650               S0      
317GND              VIA        MD0040PA00X+008850Y+070000               S0      
317GND              VIA        MD0040PA00X+008900Y+059500               S0      
317GND              VIA        MD0040PA00X+009110Y+192280               S0      
317GND              VIA        MD0040PA00X+009130Y+057700               S0      
317GND              VIA        MD0040PA00X+009220Y+055380               S0      
317GND              VIA        MD0040PA00X+009250Y+007300               S0      
317GND              VIA        MD0040PA00X+009300Y+069850               S0      
317GND              VIA        MD0040PA00X+009400Y+097180               S0      
317GND              VIA        MD0040PA00X+009600Y+058800               S0      
317GND              VIA        MD0040PA00X+009730Y+099080               S0      
317GND              VIA        MD0040PA00X+009800Y+069850               S0      
317GND              VIA        MD0040PA00X+009800Y+070300               S0      
317GND              VIA        MD0040PA00X+009800Y+070800               S0      
317GND              VIA        MD0040PA00X+001000Y+081150               S0      
317GND              VIA        MD0040PA00X+010050Y+138450               S0      
317GND              VIA        MD0040PA00X+010050Y+138900               S0      
317GND              VIA        MD0040PA00X+010130Y+039010               S0      
317GND              VIA        MD0040PA00X+010150Y+040650               S0      
317GND              VIA        MD0040PA00X+010250Y+042650               S0      
317GND              VIA        MD0040PA00X+010250Y+089350               S0      
317GND              VIA        MD0040PA00X+010291Y+067397               S0      
317GND              VIA        MD0040PA00X+010300Y+124490               S0      
317GND              VIA        MD0040PA00X+010310Y+058760               S0      
317GND              VIA        MD0040PA00X+010350Y+102850               S0      
317GND              VIA        MD0040PA00X+010350Y+104200               S0      
317GND              VIA        MD0040PA00X+010350Y+107350               S0      
317GND              VIA        MD0040PA00X+010350Y+122900               S0      
317GND              VIA        MD0040PA00X+010350Y+069550               S0      
317GND              VIA        MD0040PA00X+010350Y+090950               S0      
317GND              VIA        MD0040PA00X+010370Y+147030               S0      
317GND              VIA        MD0040PA00X+010400Y+101400               S0      
317GND              VIA        MD0040PA00X+010450Y+109500               S0      
317GND              VIA        MD0040PA00X+010450Y+120800               S0      
317GND              VIA        MD0040PA00X+010450Y+121950               S0      
317GND              VIA        MD0040PA00X+010500Y+119600               S0      
317GND              VIA        MD0040PA00X+010500Y+012500               S0      
317GND              VIA        MD0040PA00X+010500Y+014300               S0      
317GND              VIA        MD0040PA00X+010500Y+015500               S0      
317GND              VIA        MD0040PA00X+010500Y+004500               S0      
317GND              VIA        MD0040PA00X+010500Y+005500               S0      
317GND              VIA        MD0040PA00X+010500Y+095800               S0      
317GND              VIA        MD0040PA00X+010550Y+039000               S0      
317GND              VIA        MD0040PA00X+010550Y+040650               S0      
317GND              VIA        MD0040PA00X+010550Y+099600               S0      
317GND              VIA        MD0040PA00X+010650Y+100850               S0      
317GND              VIA        MD0040PA00X+010700Y+042650               S0      
317GND              VIA        MD0040PA00X+010700Y+090300               S0      
317GND              VIA        MD0040PA00X+010700Y+091800               S0      
317GND              VIA        MD0040PA00X+010711Y+067400               S0      
317GND              VIA        MD0040PA00X+010850Y+069550               S0      
317GND              VIA        MD0040PA00X+010850Y+096400               S0      
317GND              VIA        MD0040PA00X+010850Y+097100               S0      
317GND              VIA        MD0040PA00X+010900Y+108350               S0      
317GND              VIA        MD0040PA00X+011000Y+141800               S0      
317GND              VIA        MD0040PA00X+011000Y+094950               S0      
317GND              VIA        MD0040PA00X+011050Y+104150               S0      
317GND              VIA        MD0040PA00X+011050Y+105100               S0      
317GND              VIA        MD0040PA00X+011050Y+106450               S0      
317GND              VIA        MD0040PA00X+011050Y+111200               S0      
317GND              VIA        MD0040PA00X+011050Y+040650               S0      
317GND              VIA        MD0040PA00X+011120Y+042640               S0      
317GND              VIA        MD0040PA00X+011150Y+102000               S0      
317GND              VIA        MD0040PA00X+011150Y+103000               S0      
317GND              VIA        MD0040PA00X+011150Y+039000               S0      
317GND              VIA        MD0040PA00X+011200Y+124450               S0      
317GND              VIA        MD0040PA00X+011200Y+125050               S0      
317GND              VIA        MD0040PA00X+011350Y+079250               S0      
317GND              VIA        MD0040PA00X+011350Y+090950               S0      
317GND              VIA        MD0040PA00X+011380Y+128790               S0      
317GND              VIA        MD0040PA00X+011380Y+133190               S0      
317GND              VIA        MD0040PA00X+011400Y+127400               S0      
317GND              VIA        MD0040PA00X+011400Y+131800               S0      
317GND              VIA        MD0040PA00X+011400Y+137600               S0      
317GND              VIA        MD0040PA00X+011400Y+080000               S0      
317GND              VIA        MD0040PA00X+011450Y+129650               S0      
317GND              VIA        MD0040PA00X+011450Y+137050               S0      
317GND              VIA        MD0040PA00X+011450Y+080550               S0      
317GND              VIA        MD0040PA00X+011480Y+100500               S0      
317GND              VIA        MD0040PA00X+011500Y+110850               S0      
317GND              VIA        MD0040PA00X+011500Y+004500               S0      
317GND              VIA        MD0040PA00X+011500Y+070450               S0      
317GND              VIA        MD0040PA00X+011500Y+077320               S0      
317GND              VIA        MD0040PA00X+011500Y+081300               S0      
317GND              VIA        MD0040PA00X+011500Y+092000               S0      
317GND              VIA        MD0040PA00X+011520Y+078420               S0      
317GND              VIA        MD0040PA00X+011550Y+093000               S0      
317GND              VIA        MD0040PA00X+011580Y+136390               S0      
317GND              VIA        MD0040PA00X+011600Y+135000               S0      
317GND              VIA        MD0040PA00X+011605Y+090325               S0      
317GND              VIA        MD0040PA00X+011650Y+103550               S0      
317GND              VIA        MD0040PA00X+011650Y+104900               S0      
317GND              VIA        MD0040PA00X+011650Y+106250               S0      
317GND              VIA        MD0040PA00X+011650Y+107600               S0      
317GND              VIA        MD0040PA00X+011650Y+075200               S0      
317GND              VIA        MD0040PA00X+011700Y+100850               S0      
317GND              VIA        MD0040PA00X+011700Y+053000               S0      
317GND              VIA        MD0040PA00X+011750Y+102350               S0      
317GND              VIA        MD0040PA00X+011750Y+125100               S0      
317GND              VIA        MD0040PA00X+011750Y+089300               S0      
317GND              VIA        MD0040PA00X+011753Y+094884               S0      
317GND              VIA        MD0040PA00X+011800Y+012450               S0      
317GND              VIA        MD0040PA00X+011800Y+014250               S0      
317GND              VIA        MD0040PA00X+011800Y+015450               S0      
317GND              VIA        MD0040PA00X+011800Y+192200               S0      
317GND              VIA        MD0040PA00X+011800Y+005450               S0      
317GND              VIA        MD0040PA00X+011850Y+116600               S0      
317GND              VIA        MD0040PA00X+011900Y+010950               S0      
317GND              VIA        MD0040PA00X+011900Y+126900               S0      
317GND              VIA        MD0040PA00X+011900Y+067330               S0      
317GND              VIA        MD0040PA00X+011900Y+097500               S0      
317GND              VIA        MD0040PA00X+011930Y+119140               S0      
317GND              VIA        MD0040PA00X+011930Y+121940               S0      
317GND              VIA        MD0040PA00X+011930Y+124540               S0      
317GND              VIA        MD0040PA00X+011950Y+117750               S0      
317GND              VIA        MD0040PA00X+011950Y+120550               S0      
317GND              VIA        MD0040PA00X+011950Y+123150               S0      
317GND              VIA        MD0040PA00X+001200Y+127400               S0      
317GND              VIA        MD0040PA00X+001200Y+129400               S0      
317GND              VIA        MD0040PA00X+012000Y+110200               S0      
317GND              VIA        MD0040PA00X+012000Y+110800               S0      
317GND              VIA        MD0040PA00X+012000Y+071750               S0      
317GND              VIA        MD0040PA00X+012000Y+091600               S0      
317GND              VIA        MD0040PA00X+012050Y+073250               S0      
317GND              VIA        MD0040PA00X+012100Y+076790               S0      
317GND              VIA        MD0040PA00X+012100Y+077600               S0      
317GND              VIA        MD0040PA00X+012150Y+078350               S0      
317GND              VIA        MD0040PA00X+012250Y+079250               S0      
317GND              VIA        MD0040PA00X+012300Y+080000               S0      
317GND              VIA        MD0040PA00X+012300Y+080850               S0      
317GND              VIA        MD0040PA00X+012350Y+081600               S0      
317GND              VIA        MD0040PA00X+012350Y+084250               S0      
317GND              VIA        MD0040PA00X+012380Y+128390               S0      
317GND              VIA        MD0040PA00X+012380Y+131190               S0      
317GND              VIA        MD0040PA00X+012380Y+133790               S0      
317GND              VIA        MD0040PA00X+012380Y+136590               S0      
317GND              VIA        MD0040PA00X+012400Y+127000               S0      
317GND              VIA        MD0040PA00X+012400Y+129800               S0      
317GND              VIA        MD0040PA00X+012400Y+132400               S0      
317GND              VIA        MD0040PA00X+012400Y+135200               S0      
317GND              VIA        MD0040PA00X+012400Y+137650               S0      
317GND              VIA        MD0040PA00X+012400Y+007450               S0      
317GND              VIA        MD0040PA00X+012400Y+090900               S0      
317GND              VIA        MD0040PA00X+012400Y+097150               S0      
317GND              VIA        MD0040PA00X+012450Y+082510               S0      
317GND              VIA        MD0040PA00X+012450Y+085800               S0      
317GND              VIA        MD0040PA00X+012450Y+087650               S0      
317GND              VIA        MD0040PA00X+012462Y+095924               S0      
317GND              VIA        MD0040PA00X+012480Y+069660               S0      
317GND              VIA        MD0040PA00X+001250Y+178250               S0      
317GND              VIA        MD0040PA00X+001250Y+195900               S0      
317GND              VIA        MD0040PA00X+001250Y+019750               S0      
317GND              VIA        MD0040PA00X+001250Y+026650               S0      
317GND              VIA        MD0040PA00X+012500Y+004500               S0      
317GND              VIA        MD0040PA00X+012500Y+073400               S0      
317GND              VIA        MD0040PA00X+012500Y+075100               S0      
317GND              VIA        MD0040PA00X+012500Y+075850               S0      
317GND              VIA        MD0040PA00X+012500Y+086850               S0      
317GND              VIA        MD0040PA00X+012500Y+096700               S0      
317GND              VIA        MD0040PA00X+012550Y+074150               S0      
317GND              VIA        MD0040PA00X+012550Y+092000               S0      
317GND              VIA        MD0040PA00X+012550Y+094400               S0      
317GND              VIA        MD0040PA00X+001260Y+175380               S0      
317GND              VIA        MD0040PA00X+001260Y+179280               S0      
317GND              VIA        MD0040PA00X+012600Y+089250               S0      
317GND              VIA        MD0040PA00X+012600Y+093000               S0      
317GND              VIA        MD0040PA00X+012600Y+095400               S0      
317GND              VIA        MD0040PA00X+012660Y+146150               S0      
317GND              VIA        MD0040PA00X+012700Y+090300               S0      
317GND              VIA        MD0040PA00X+012770Y+011920               S0      
317GND              VIA        MD0040PA00X+001280Y+186370               S0      
317GND              VIA        MD0040PA00X+012850Y+008900               S0      
317GND              VIA        MD0040PA00X+012870Y+010420               S0      
317GND              VIA        MD0040PA00X+001290Y+176520               S0      
317GND              VIA        MD0040PA00X+012900Y+016010               S0      
317GND              VIA        MD0040PA00X+012900Y+077450               S0      
317GND              VIA        MD0040PA00X+012920Y+083040               S0      
317GND              VIA        MD0040PA00X+012950Y+078200               S0      
317GND              VIA        MD0040PA00X+012950Y+079250               S0      
317GND              VIA        MD0040PA00X+012980Y+069680               S0      
317GND              VIA        MD0040PA00X+012980Y+081350               S0      
317GND              VIA        MD0040PA00X+001300Y+021250               S0      
317GND              VIA        MD0040PA00X+001300Y+024400               S0      
317GND              VIA        MD0040PA00X+001300Y+032100               S0      
317GND              VIA        MD0040PA00X+013000Y+073650               S0      
317GND              VIA        MD0040PA00X+013000Y+080000               S0      
317GND              VIA        MD0040PA00X+013050Y+096600               S0      
317GND              VIA        MD0040PA00X+013090Y+025910               S0      
317GND              VIA        MD0040PA00X+001310Y+172890               S0      
317GND              VIA        MD0040PA00X+001310Y+174260               S0      
317GND              VIA        MD0040PA00X+001310Y+193390               S0      
317GND              VIA        MD0040PA00X+013100Y+013810               S0      
317GND              VIA        MD0040PA00X+013100Y+015010               S0      
317GND              VIA        MD0040PA00X+013180Y+028970               S0      
317GND              VIA        MD0040PA00X+013220Y+142480               S0      
317GND              VIA        MD0040PA00X+013350Y+146710               S0      
317GND              VIA        MD0040PA00X+013350Y+093800               S0      
317GND              VIA        MD0040PA00X+013400Y+099050               S0      
317GND              VIA        MD0040PA00X+013410Y+067450               S0      
317GND              VIA        MD0040PA00X+013450Y+084050               S0      
317GND              VIA        MD0040PA00X+013450Y+088550               S0      
317GND              VIA        MD0040PA00X+001350Y+136500               S0      
317GND              VIA        MD0040PA00X+001350Y+023050               S0      
317GND              VIA        MD0040PA00X+001350Y+027900               S0      
317GND              VIA        MD0040PA00X+001350Y+029500               S0      
317GND              VIA        MD0040PA00X+001350Y+030350               S0      
317GND              VIA        MD0040PA00X+001351Y+059799               S0      
317GND              VIA        MD0040PA00X+013500Y+004500               S0      
317GND              VIA        MD0040PA00X+013500Y+005000               S0      
317GND              VIA        MD0040PA00X+013500Y+007000               S0      
317GND              VIA        MD0040PA00X+013500Y+089300               S0      
317GND              VIA        MD0040PA00X+013500Y+091800               S0      
317GND              VIA        MD0040PA00X+013500Y+097550               S0      
317GND              VIA        MD0040PA00X+013550Y+090900               S0      
317GND              VIA        MD0040PA00X+013550Y+092750               S0      
317GND              VIA        MD0040PA00X+013650Y+096700               S0      
317GND              VIA        MD0040PA00X+013700Y+142920               S0      
317GND              VIA        MD0040PA00X+013720Y+012360               S0      
317GND              VIA        MD0040PA00X+013750Y+087650               S0      
317GND              VIA        MD0040PA00X+013750Y+090300               S0      
317GND              VIA        MD0040PA00X+013790Y+017140               S0      
317GND              VIA        MD0040PA00X+013880Y+016210               S0      
317GND              VIA        MD0040PA00X+001400Y+106000               S0      
317GND              VIA        MD0040PA00X+001400Y+107400               S0      
317GND              VIA        MD0040PA00X+001400Y+108600               S0      
317GND              VIA        MD0040PA00X+001400Y+110000               S0      
317GND              VIA        MD0040PA00X+001400Y+018400               S0      
317GND              VIA        MD0040PA00X+001400Y+061400               S0      
317GND              VIA        MD0040PA00X+001400Y+065900               S0      
317GND              VIA        MD0040PA00X+014050Y+084650               S0      
317GND              VIA        MD0040PA00X+014070Y+057660               S0      
317GND              VIA        MD0040PA00X+014100Y+093850               S0      
317GND              VIA        MD0040PA00X+014130Y+029810               S0      
317GND              VIA        MD0040PA00X+014150Y+167300               S0      
317GND              VIA        MD0040PA00X+014180Y+055925               S0      
317GND              VIA        MD0040PA00X+014300Y+091050               S0      
317GND              VIA        MD0040PA00X+014400Y+091950               S0      
317GND              VIA        MD0040PA00X+014400Y+092900               S0      
317GND              VIA        MD0040PA00X+014460Y+053380               S0      
317GND              VIA        MD0040PA00X+001450Y+010050               S0      
317GND              VIA        MD0040PA00X+001450Y+011250               S0      
317GND              VIA        MD0040PA00X+001450Y+184200               S0      
317GND              VIA        MD0040PA00X+014500Y+004500               S0      
317GND              VIA        MD0040PA00X+014550Y+060400               S0      
317GND              VIA        MD0040PA00X+014550Y+085650               S0      
317GND              VIA        MD0040PA00X+014550Y+088500               S0      
317GND              VIA        MD0040PA00X+014600Y+089300               S0      
317GND              VIA        MD0040PA00X+014650Y+124150               S0      
317GND              VIA        MD0040PA00X+014650Y+013186               S0      
317GND              VIA        MD0040PA00X+014650Y+141762               S0      
317GND              VIA        MD0040PA00X+014700Y+126550               S0      
317GND              VIA        MD0040PA00X+014700Y+134800               S0      
317GND              VIA        MD0040PA00X+014700Y+137700               S0      
317GND              VIA        MD0040PA00X+014750Y+116550               S0      
317GND              VIA        MD0040PA00X+014750Y+118600               S0      
317GND              VIA        MD0040PA00X+014750Y+122150               S0      
317GND              VIA        MD0040PA00X+014750Y+128800               S0      
317GND              VIA        MD0040PA00X+014750Y+131100               S0      
317GND              VIA        MD0040PA00X+014750Y+133200               S0      
317GND              VIA        MD0040PA00X+014750Y+136650               S0      
317GND              VIA        MD0040PA00X+014750Y+055150               S0      
317GND              VIA        MD0040PA00X+014760Y+015090               S0      
317GND              VIA        MD0040PA00X+014969Y+146001               S0      
317GND              VIA        MD0040PA00X+001500Y+013150               S0      
317GND              VIA        MD0040PA00X+001500Y+185490               S0      
317GND              VIA        MD0040PA00X+015050Y+059600               S0      
317GND              VIA        MD0040PA00X+015300Y+009050               S0      
317GND              VIA        MD0040PA00X+015350Y+057436               S0      
317GND              VIA        MD0040PA00X+015350Y+094100               S0      
317GND              VIA        MD0040PA00X+015400Y+010550               S0      
317GND              VIA        MD0040PA00X+015400Y+007550               S0      
317GND              VIA        MD0040PA00X+015450Y+092650               S0      
317GND              VIA        MD0040PA00X+015460Y+111100               S0      
317GND              VIA        MD0040PA00X+015470Y+090970               S0      
317GND              VIA        MD0040PA00X+001550Y+014350               S0      
317GND              VIA        MD0040PA00X+001550Y+194250               S0      
317GND              VIA        MD0040PA00X+015500Y+004500               S0      
317GND              VIA        MD0040PA00X+015630Y+087720               S0      
317GND              VIA        MD0040PA00X+015650Y+088900               S0      
317GND              VIA        MD0040PA00X+015700Y+110150               S0      
317GND              VIA        MD0040PA00X+015750Y+085800               S0      
317GND              VIA        MD0040PA00X+015850Y+107580               S0      
317GND              VIA        MD0040PA00X+015860Y+111079               S0      
317GND              VIA        MD0040PA00X+015950Y+108750               S0      
317GND              VIA        MD0040PA00X+015970Y+065200               S0      
317GND              VIA        MD0040PA00X+001600Y+100000               S0      
317GND              VIA        MD0040PA00X+001600Y+101400               S0      
317GND              VIA        MD0040PA00X+001600Y+103200               S0      
317GND              VIA        MD0040PA00X+001600Y+104600               S0      
317GND              VIA        MD0040PA00X+001600Y+111000               S0      
317GND              VIA        MD0040PA00X+001600Y+112400               S0      
317GND              VIA        MD0040PA00X+001600Y+113400               S0      
317GND              VIA        MD0040PA00X+001600Y+114800               S0      
317GND              VIA        MD0040PA00X+001600Y+116200               S0      
317GND              VIA        MD0040PA00X+001600Y+117600               S0      
317GND              VIA        MD0040PA00X+001600Y+124400               S0      
317GND              VIA        MD0040PA00X+001600Y+126200               S0      
317GND              VIA        MD0040PA00X+001600Y+081400               S0      
317GND              VIA        MD0040PA00X+001600Y+082800               S0      
317GND              VIA        MD0040PA00X+001600Y+084200               S0      
317GND              VIA        MD0040PA00X+001600Y+085600               S0      
317GND              VIA        MD0040PA00X+001600Y+090600               S0      
317GND              VIA        MD0040PA00X+001600Y+094800               S0      
317GND              VIA        MD0040PA00X+001600Y+096200               S0      
317GND              VIA        MD0040PA00X+001600Y+097600               S0      
317GND              VIA        MD0040PA00X+001600Y+099000               S0      
317GND              VIA        MD0040PA00X+016050Y+105350               S0      
317GND              VIA        MD0040PA00X+016050Y+106700               S0      
317GND              VIA        MD0040PA00X+016050Y+187750               S0      
317GND              VIA        MD0040PA00X+001610Y+195070               S0      
317GND              VIA        MD0040PA00X+001610Y+079460               S0      
317GND              VIA        MD0040PA00X+016100Y+190150               S0      
317GND              VIA        MD0040PA00X+016230Y+065910               S0      
317GND              VIA        MD0040PA00X+016334Y+118120               S0      
317GND              VIA        MD0040PA00X+016350Y+080550               S0      
317GND              VIA        MD0040PA00X+016400Y+005550               S0      
317GND              VIA        MD0040PA00X+016450Y+129950               S0      
317GND              VIA        MD0040PA00X+016470Y+103360               S0      
317GND              VIA        MD0040PA00X+016495Y+061570               S0      
317GND              VIA        MD0040PA00X+001650Y+017500               S0      
317GND              VIA        MD0040PA00X+016500Y+109700               S0      
317GND              VIA        MD0040PA00X+016500Y+126450               S0      
317GND              VIA        MD0040PA00X+016500Y+004500               S0      
317GND              VIA        MD0040PA00X+016500Y+078600               S0      
317GND              VIA        MD0040PA00X+016530Y+014520               S0      
317GND              VIA        MD0040PA00X+016550Y+067750               S0      
317GND              VIA        MD0040PA00X+016560Y+063027               S0      
317GND              VIA        MD0040PA00X+016600Y+108000               S0      
317GND              VIA        MD0040PA00X+016630Y+102130               S0      
317GND              VIA        MD0040PA00X+016700Y+013050               S0      
317GND              VIA        MD0040PA00X+016700Y+009300               S0      
317GND              VIA        MD0040PA00X+016730Y+065380               S0      
317GND              VIA        MD0040PA00X+016900Y+079550               S0      
317GND              VIA        MD0040PA00X+016910Y+072210               S0      
317GND              VIA        MD0040PA00X+001700Y+003650               S0      
317GND              VIA        MD0040PA00X+017000Y+108950               S0      
317GND              VIA        MD0040PA00X+017000Y+110300               S0      
317GND              VIA        MD0040PA00X+017050Y+012050               S0      
317GND              VIA        MD0040PA00X+017100Y+103250               S0      
317GND              VIA        MD0040PA00X+017100Y+104600               S0      
317GND              VIA        MD0040PA00X+017100Y+106800               S0      
317GND              VIA        MD0040PA00X+017150Y+010550               S0      
317GND              VIA        MD0040PA00X+017150Y+081950               S0      
317GND              VIA        MD0040PA00X+017150Y+112955               S0      
317GND              VIA        MD0040PA00X+017160Y+059540               S0      
317GND              VIA        MD0040PA00X+017200Y+075750               S0      
317GND              VIA        MD0040PA00X+017300Y+108200               S0      
317GND              VIA        MD0040PA00X+017338Y+143250               S0      
317GND              VIA        MD0040PA00X+017350Y+015150               S0      
317GND              VIA        MD0040PA00X+017350Y+076400               S0      
317GND              VIA        MD0040PA00X+017350Y+077750               S0      
317GND              VIA        MD0040PA00X+017400Y+101240               S0      
317GND              VIA        MD0040PA00X+017400Y+005550               S0      
317GND              VIA        MD0040PA00X+017450Y+014350               S0      
317GND              VIA        MD0040PA00X+017500Y+105900               S0      
317GND              VIA        MD0040PA00X+017500Y+107250               S0      
317GND              VIA        MD0040PA00X+017500Y+004500               S0      
317GND              VIA        MD0040PA00X+017500Y+078650               S0      
317GND              VIA        MD0040PA00X+017580Y+061764               S0      
317GND              VIA        MD0040PA00X+017600Y+101850               S0      
317GND              VIA        MD0040PA00X+017600Y+013100               S0      
317GND              VIA        MD0040PA00X+017600Y+066550               S0      
317GND              VIA        MD0040PA00X+017600Y+067900               S0      
317GND              VIA        MD0040PA00X+001770Y+128300               S0      
317GND              VIA        MD0040PA00X+017710Y+112980               S0      
317GND              VIA        MD0040PA00X+017750Y+081200               S0      
317GND              VIA        MD0040PA00X+017750Y+082650               S0      
317GND              VIA        MD0040PA00X+017800Y+079750               S0      
317GND              VIA        MD0040PA00X+017864Y+120252               S0      
317GND              VIA        MD0040PA00X+001800Y+060800               S0      
317GND              VIA        MD0040PA00X+001800Y+071200               S0      
317GND              VIA        MD0040PA00X+001800Y+072400               S0      
317GND              VIA        MD0040PA00X+001800Y+073250               S0      
317GND              VIA        MD0040PA00X+001800Y+087000               S0      
317GND              VIA        MD0040PA00X+001800Y+088400               S0      
317GND              VIA        MD0040PA00X+001800Y+092000               S0      
317GND              VIA        MD0040PA00X+001800Y+093400               S0      
317GND              VIA        MD0040PA00X+018050Y+011200               S0      
317GND              VIA        MD0040PA00X+018050Y+059500               S0      
317GND              VIA        MD0040PA00X+018050Y+062777               S0      
317GND              VIA        MD0040PA00X+018085Y+034880               S0      
317GND              VIA        MD0040PA00X+018100Y+105100               S0      
317GND              VIA        MD0040PA00X+018100Y+107950               S0      
317GND              VIA        MD0040PA00X+018100Y+109850               S0      
317GND              VIA        MD0040PA00X+018100Y+111250               S0      
317GND              VIA        MD0040PA00X+018100Y+071550               S0      
317GND              VIA        MD0040PA00X+018100Y+072900               S0      
317GND              VIA        MD0040PA00X+018110Y+036405               S0      
317GND              VIA        MD0040PA00X+018150Y+073850               S0      
317GND              VIA        MD0040PA00X+018170Y+076840               S0      
317GND              VIA        MD0040PA00X+018180Y+036900               S0      
317GND              VIA        MD0040PA00X+018200Y+101600               S0      
317GND              VIA        MD0040PA00X+018200Y+102950               S0      
317GND              VIA        MD0040PA00X+018200Y+095050               S0      
317GND              VIA        MD0040PA00X+018250Y+104150               S0      
317GND              VIA        MD0040PA00X+018250Y+074500               S0      
317GND              VIA        MD0040PA00X+018250Y+075850               S0      
317GND              VIA        MD0040PA00X+018260Y+054690               S0      
317GND              VIA        MD0040PA00X+018350Y+106550               S0      
317GND              VIA        MD0040PA00X+018350Y+124150               S0      
317GND              VIA        MD0040PA00X+018350Y+069800               S0      
317GND              VIA        MD0040PA00X+018400Y+005550               S0      
317GND              VIA        MD0040PA00X+018400Y+098750               S0      
317GND              VIA        MD0040PA00X+018450Y+032550               S0      
317GND              VIA        MD0040PA00X+018450Y+070850               S0      
317GND              VIA        MD0040PA00X+018450Y+086550               S0      
317GND              VIA        MD0040PA00X+018450Y+087900               S0      
317GND              VIA        MD0040PA00X+018470Y+066390               S0      
317GND              VIA        MD0040PA00X+001850Y+089650               S0      
317GND              VIA        MD0040PA00X+018500Y+004500               S0      
317GND              VIA        MD0040PA00X+018500Y+067350               S0      
317GND              VIA        MD0040PA00X+018500Y+084350               S0      
317GND              VIA        MD0040PA00X+018500Y+091750               S0      
317GND              VIA        MD0040PA00X+018550Y+015150               S0      
317GND              VIA        MD0040PA00X+001860Y+187140               S0      
317GND              VIA        MD0040PA00X+018600Y+014300               S0      
317GND              VIA        MD0040PA00X+018660Y+042575               S0      
317GND              VIA        MD0040PA00X+018700Y+089100               S0      
317GND              VIA        MD0040PA00X+018750Y+109000               S0      
317GND              VIA        MD0040PA00X+018750Y+110350               S0      
317GND              VIA        MD0040PA00X+018750Y+013050               S0      
317GND              VIA        MD0040PA00X+018750Y+033800               S0      
317GND              VIA        MD0040PA00X+018790Y+156660               S0      
317GND              VIA        MD0040PA00X+018790Y+078530               S0      
317GND              VIA        MD0040PA00X+018810Y+068910               S0      
317GND              VIA        MD0040PA00X+018830Y+036860               S0      
317GND              VIA        MD0040PA00X+018850Y+036410               S0      
317GND              VIA        MD0040PA00X+018940Y+154410               S0      
317GND              VIA        MD0040PA00X+018950Y+012000               S0      
317GND              VIA        MD0040PA00X+018950Y+157700               S0      
317GND              VIA        MD0040PA00X+019000Y+105200               S0      
317GND              VIA        MD0040PA00X+019000Y+162200               S0      
317GND              VIA        MD0040PA00X+019000Y+082350               S0      
317GND              VIA        MD0040PA00X+019050Y+010500               S0      
317GND              VIA        MD0040PA00X+019050Y+192400               S0      
317GND              VIA        MD0040PA00X+019050Y+055050               S0      
317GND              VIA        MD0040PA00X+019050Y+083100               S0      
317GND              VIA        MD0040PA00X+019150Y+159500               S0      
317GND              VIA        MD0040PA00X+019150Y+163100               S0      
317GND              VIA        MD0040PA00X+019150Y+069250               S0      
317GND              VIA        MD0040PA00X+019150Y+071050               S0      
317GND              VIA        MD0040PA00X+019150Y+072400               S0      
317GND              VIA        MD0040PA00X+019150Y+074650               S0      
317GND              VIA        MD0040PA00X+019150Y+076000               S0      
317GND              VIA        MD0040PA00X+019160Y+020690               S0      
317GND              VIA        MD0040PA00X+019170Y+018650               S0      
317GND              VIA        MD0040PA00X+019180Y+128090               S0      
317GND              VIA        MD0040PA00X+019180Y+022110               S0      
317GND              VIA        MD0040PA00X+019180Y+023490               S0      
317GND              VIA        MD0040PA00X+019190Y+016770               S0      
317GND              VIA        MD0040PA00X+019190Y+024460               S0      
317GND              VIA        MD0040PA00X+019190Y+053820               S0      
317GND              VIA        MD0040PA00X+019200Y+158600               S0      
317GND              VIA        MD0040PA00X+019200Y+054350               S0      
317GND              VIA        MD0040PA00X+019200Y+086550               S0      
317GND              VIA        MD0040PA00X+019200Y+087900               S0      
317GND              VIA        MD0040PA00X+019200Y+092100               S0      
317GND              VIA        MD0040PA00X+019200Y+093450               S0      
317GND              VIA        MD0040PA00X+019200Y+094850               S0      
317GND              VIA        MD0040PA00X+019200Y+096200               S0      
317GND              VIA        MD0040PA00X+019230Y+041095               S0      
317GND              VIA        MD0040PA00X+019240Y+040190               S0      
317GND              VIA        MD0040PA00X+019240Y+052940               S0      
317GND              VIA        MD0040PA00X+019241Y+041766               S0      
317GND              VIA        MD0040PA00X+019247Y+039735               S0      
317GND              VIA        MD0040PA00X+019250Y+064500               S0      
317GND              VIA        MD0040PA00X+019250Y+065850               S0      
317GND              VIA        MD0040PA00X+019250Y+083950               S0      
317GND              VIA        MD0040PA00X+019250Y+085300               S0      
317GND              VIA        MD0040PA00X+019250Y+097200               S0      
317GND              VIA        MD0040PA00X+019250Y+098550               S0      
317GND              VIA        MD0040PA00X+019260Y+039260               S0      
317GND              VIA        MD0040PA00X+019260Y+063300               S0      
317GND              VIA        MD0040PA00X+019300Y+155650               S0      
317GND              VIA        MD0040PA00X+019300Y+156250               S0      
317GND              VIA        MD0040PA00X+019310Y+067900               S0      
317GND              VIA        MD0040PA00X+019350Y+102900               S0      
317GND              VIA        MD0040PA00X+019350Y+104250               S0      
317GND              VIA        MD0040PA00X+019370Y+059500               S0      
317GND              VIA        MD0040PA00X+019400Y+005550               S0      
317GND              VIA        MD0040PA00X+019400Y+061500               S0      
317GND              VIA        MD0040PA00X+019400Y+062850               S0      
317GND              VIA        MD0040PA00X+019400Y+089350               S0      
317GND              VIA        MD0040PA00X+019400Y+090700               S0      
317GND              VIA        MD0040PA00X+019440Y+187670               S0      
317GND              VIA        MD0040PA00X+019440Y+058600               S0      
317GND              VIA        MD0040PA00X+019450Y+110050               S0      
317GND              VIA        MD0040PA00X+019450Y+154600               S0      
317GND              VIA        MD0040PA00X+019450Y+076900               S0      
317GND              VIA        MD0040PA00X+019450Y+078250               S0      
317GND              VIA        MD0040PA00X+019500Y+106100               S0      
317GND              VIA        MD0040PA00X+019500Y+107450               S0      
317GND              VIA        MD0040PA00X+019500Y+108650               S0      
317GND              VIA        MD0040PA00X+019500Y+004500               S0      
317GND              VIA        MD0040PA00X+019500Y+067000               S0      
317GND              VIA        MD0040PA00X+019550Y+100100               S0      
317GND              VIA        MD0040PA00X+019550Y+101450               S0      
317GND              VIA        MD0040PA00X+019550Y+153050               S0      
317GND              VIA        MD0040PA00X+019550Y+190500               S0      
317GND              VIA        MD0040PA00X+019550Y+073900               S0      
317GND              VIA        MD0040PA00X+019600Y+071850               S0      
317GND              VIA        MD0040PA00X+019600Y+078950               S0      
317GND              VIA        MD0040PA00X+019650Y+165600               S0      
317GND              VIA        MD0040PA00X+019650Y+180050               S0      
317GND              VIA        MD0040PA00X+019650Y+188200               S0      
317GND              VIA        MD0040PA00X+019650Y+064150               S0      
317GND              VIA        MD0040PA00X+019650Y+079700               S0      
317GND              VIA        MD0040PA00X+019680Y+082850               S0      
317GND              VIA        MD0040PA00X+001972Y+026720               S0      
317GND              VIA        MD0040PA00X+019700Y+155150               S0      
317GND              VIA        MD0040PA00X+019700Y+169150               S0      
317GND              VIA        MD0040PA00X+019700Y+171300               S0      
317GND              VIA        MD0040PA00X+019700Y+173550               S0      
317GND              VIA        MD0040PA00X+019700Y+183850               S0      
317GND              VIA        MD0040PA00X+019700Y+070400               S0      
317GND              VIA        MD0040PA00X+019700Y+081500               S0      
317GND              VIA        MD0040PA00X+019750Y+015150               S0      
317GND              VIA        MD0040PA00X+019750Y+159300               S0      
317GND              VIA        MD0040PA00X+019750Y+175400               S0      
317GND              VIA        MD0040PA00X+019750Y+177650               S0      
317GND              VIA        MD0040PA00X+019750Y+186000               S0      
317GND              VIA        MD0040PA00X+019750Y+068500               S0      
317GND              VIA        MD0040PA00X+019750Y+075300               S0      
317GND              VIA        MD0040PA00X+001980Y+131540               S0      
317GND              VIA        MD0040PA00X+019800Y+163250               S0      
317GND              VIA        MD0040PA00X+019800Y+164750               S0      
317GND              VIA        MD0040PA00X+019800Y+181850               S0      
317GND              VIA        MD0040PA00X+019850Y+158400               S0      
317GND              VIA        MD0040PA00X+019900Y+161950               S0      
317GND              VIA        MD0040PA00X+002000Y+000600               S0      
317GND              VIA        MD0040PA00X+002000Y+069600               S0      
317GND              VIA        MD0040PA00X+020000Y+010000               S0      
317GND              VIA        MD0040PA00X+020000Y+012000               S0      
317GND              VIA        MD0040PA00X+020000Y+014000               S0      
317GND              VIA        MD0040PA00X+020000Y+042050               S0      
317GND              VIA        MD0040PA00X+020000Y+005500               S0      
317GND              VIA        MD0040PA00X+020000Y+006500               S0      
317GND              VIA        MD0040PA00X+020000Y+007500               S0      
317GND              VIA        MD0040PA00X+020000Y+008500               S0      
317GND              VIA        MD0040PA00X+020050Y+019590               S0      
317GND              VIA        MD0040PA00X+020050Y+023500               S0      
317GND              VIA        MD0040PA00X+020050Y+043750               S0      
317GND              VIA        MD0040PA00X+020100Y+109300               S0      
317GND              VIA        MD0040PA00X+020100Y+110650               S0      
317GND              VIA        MD0040PA00X+020100Y+192300               S0      
317GND              VIA        MD0040PA00X+020100Y+022250               S0      
317GND              VIA        MD0040PA00X+020100Y+043050               S0      
317GND              VIA        MD0040PA00X+020109Y+018170               S0      
317GND              VIA        MD0040PA00X+020109Y+028260               S0      
317GND              VIA        MD0040PA00X+020109Y+030550               S0      
317GND              VIA        MD0040PA00X+020109Y+031550               S0      
317GND              VIA        MD0040PA00X+020109Y+038840               S0      
317GND              VIA        MD0040PA00X+020109Y+040700               S0      
317GND              VIA        MD0040PA00X+020109Y+052950               S0      
317GND              VIA        MD0040PA00X+020109Y+055800               S0      
317GND              VIA        MD0040PA00X+020109Y+057060               S0      
317GND              VIA        MD0040PA00X+020150Y+190050               S0      
317GND              VIA        MD0040PA00X+020150Y+020800               S0      
317GND              VIA        MD0040PA00X+020150Y+037800               S0      
317GND              VIA        MD0040PA00X+020150Y+039750               S0      
317GND              VIA        MD0040PA00X+020150Y+053500               S0      
317GND              VIA        MD0040PA00X+020150Y+054450               S0      
317GND              VIA        MD0040PA00X+020150Y+055250               S0      
317GND              VIA        MD0040PA00X+020150Y+056400               S0      
317GND              VIA        MD0040PA00X+020150Y+062150               S0      
317GND              VIA        MD0040PA00X+020150Y+083550               S0      
317GND              VIA        MD0040PA00X+020200Y+025400               S0      
317GND              VIA        MD0040PA00X+020200Y+026400               S0      
317GND              VIA        MD0040PA00X+020200Y+027400               S0      
317GND              VIA        MD0040PA00X+020200Y+029500               S0      
317GND              VIA        MD0040PA00X+020200Y+032800               S0      
317GND              VIA        MD0040PA00X+020200Y+034000               S0      
317GND              VIA        MD0040PA00X+020200Y+035300               S0      
317GND              VIA        MD0040PA00X+020200Y+036650               S0      
317GND              VIA        MD0040PA00X+020200Y+057800               S0      
317GND              VIA        MD0040PA00X+020200Y+058600               S0      
317GND              VIA        MD0040PA00X+020200Y+059500               S0      
317GND              VIA        MD0040PA00X+020200Y+060750               S0      
317GND              VIA        MD0040PA00X+020200Y+065050               S0      
317GND              VIA        MD0040PA00X+020200Y+067650               S0      
317GND              VIA        MD0040PA00X+020200Y+071000               S0      
317GND              VIA        MD0040PA00X+020200Y+074050               S0      
317GND              VIA        MD0040PA00X+020200Y+076500               S0      
317GND              VIA        MD0040PA00X+020200Y+078600               S0      
317GND              VIA        MD0040PA00X+020200Y+080750               S0      
317GND              VIA        MD0040PA00X+002150Y+024150               S0      
317GND              VIA        MD0040PA00X+002200Y+123200               S0      
317GND              VIA        MD0040PA00X+002200Y+074600               S0      
317GND              VIA        MD0040PA00X+002250Y+019000               S0      
317GND              VIA        MD0040PA00X+002300Y+067750               S0      
317GND              VIA        MD0040PA00X+002305Y+086125               S0      
317GND              VIA        MD0040PA00X+002350Y+012400               S0      
317GND              VIA        MD0040PA00X+002370Y+036390               S0      
317GND              VIA        MD0040PA00X+002380Y+041070               S0      
317GND              VIA        MD0040PA00X+002400Y+118000               S0      
317GND              VIA        MD0040PA00X+002400Y+021200               S0      
317GND              VIA        MD0040PA00X+002400Y+075600               S0      
317GND              VIA        MD0040PA00X+002400Y+084600               S0      
317GND              VIA        MD0040PA00X+002420Y+183670               S0      
317GND              VIA        MD0040PA00X+002450Y+188400               S0      
317GND              VIA        MD0040PA00X+002450Y+085350               S0      
317GND              VIA        MD0040PA00X+002455Y+115325               S0      
317GND              VIA        MD0040PA00X+002480Y+192650               S0      
317GND              VIA        MD0040PA00X+002500Y+196250               S0      
317GND              VIA        MD0040PA00X+002505Y+097125               S0      
317GND              VIA        MD0040PA00X+002600Y+101000               S0      
317GND              VIA        MD0040PA00X+002600Y+043250               S0      
317GND              VIA        MD0040PA00X+002600Y+065650               S0      
317GND              VIA        MD0040PA00X+002600Y+073200               S0      
317GND              VIA        MD0040PA00X+002600Y+008700               S0      
317GND              VIA        MD0040PA00X+002605Y+082825               S0      
317GND              VIA        MD0040PA00X+002605Y+093825               S0      
317GND              VIA        MD0040PA00X+002610Y+108860               S0      
317GND              VIA        MD0040PA00X+002650Y+044000               S0      
317GND              VIA        MD0040PA00X+002660Y+113240               S0      
317GND              VIA        MD0040PA00X+002660Y+157010               S0      
317GND              VIA        MD0040PA00X+002670Y+157980               S0      
317GND              VIA        MD0040PA00X+002690Y+154790               S0      
317GND              VIA        MD0040PA00X+002690Y+155910               S0      
317GND              VIA        MD0040PA00X+002700Y+018200               S0      
317GND              VIA        MD0040PA00X+002700Y+037100               S0      
317GND              VIA        MD0040PA00X+002700Y+037750               S0      
317GND              VIA        MD0040PA00X+002700Y+038400               S0      
317GND              VIA        MD0040PA00X+002700Y+038950               S0      
317GND              VIA        MD0040PA00X+002700Y+075000               S0      
317GND              VIA        MD0040PA00X+002722Y+109700               S0      
317GND              VIA        MD0040PA00X+002750Y+187450               S0      
317GND              VIA        MD0040PA00X+002755Y+102925               S0      
317GND              VIA        MD0040PA00X+002800Y+107200               S0      
317GND              VIA        MD0040PA00X+002800Y+126600               S0      
317GND              VIA        MD0040PA00X+002800Y+128600               S0      
317GND              VIA        MD0040PA00X+002800Y+130000               S0      
317GND              VIA        MD0040PA00X+002800Y+132000               S0      
317GND              VIA        MD0040PA00X+002800Y+070600               S0      
317GND              VIA        MD0040PA00X+002800Y+099200               S0      
317GND              VIA        MD0040PA00X+002900Y+167100               S0      
317GND              VIA        MD0040PA00X+002900Y+020050               S0      
317GND              VIA        MD0040PA00X+002950Y+149580               S0      
317GND              VIA        MD0040PA00X+002950Y+036450               S0      
317GND              VIA        MD0040PA00X+002950Y+005300               S0      
317GND              VIA        MD0040PA00X+002970Y+019140               S0      
317GND              VIA        MD0040PA00X+003000Y+124000               S0      
317GND              VIA        MD0040PA00X+003000Y+173100               S0      
317GND              VIA        MD0040PA00X+003000Y+078200               S0      
317GND              VIA        MD0040PA00X+003050Y+081950               S0      
317GND              VIA        MD0040PA00X+003080Y+013030               S0      
317GND              VIA        MD0040PA00X+003080Y+140390               S0      
317GND              VIA        MD0040PA00X+003100Y+070050               S0      
317GND              VIA        MD0040PA00X+003100Y+074700               S0      
317GND              VIA        MD0040PA00X+003150Y+122200               S0      
317GND              VIA        MD0040PA00X+003150Y+139750               S0      
317GND              VIA        MD0040PA00X+003150Y+187850               S0      
317GND              VIA        MD0040PA00X+003150Y+000550               S0      
317GND              VIA        MD0040PA00X+003200Y+111400               S0      
317GND              VIA        MD0040PA00X+003200Y+139150               S0      
317GND              VIA        MD0040PA00X+003200Y+004000               S0      
317GND              VIA        MD0040PA00X+003200Y+066600               S0      
317GND              VIA        MD0040PA00X+003200Y+084400               S0      
317GND              VIA        MD0040PA00X+003200Y+085800               S0      
317GND              VIA        MD0040PA00X+003200Y+087200               S0      
317GND              VIA        MD0040PA00X+003200Y+088600               S0      
317GND              VIA        MD0040PA00X+003310Y+158740               S0      
317GND              VIA        MD0040PA00X+003350Y+095300               S0      
317GND              VIA        MD0040PA00X+003350Y+096250               S0      
317GND              VIA        MD0040PA00X+003355Y+108010               S0      
317GND              VIA        MD0040PA00X+003360Y+102990               S0      
317GND              VIA        MD0040PA00X+003400Y+100800               S0      
317GND              VIA        MD0040PA00X+003400Y+101750               S0      
317GND              VIA        MD0040PA00X+003400Y+107200               S0      
317GND              VIA        MD0040PA00X+003400Y+110200               S0      
317GND              VIA        MD0040PA00X+003400Y+114400               S0      
317GND              VIA        MD0040PA00X+003400Y+131200               S0      
317GND              VIA        MD0040PA00X+003400Y+146590               S0      
317GND              VIA        MD0040PA00X+003400Y+147760               S0      
317GND              VIA        MD0040PA00X+003400Y+093450               S0      
317GND              VIA        MD0040PA00X+003400Y+094400               S0      
317GND              VIA        MD0040PA00X+003400Y+097450               S0      
317GND              VIA        MD0040PA00X+003400Y+098400               S0      
317GND              VIA        MD0040PA00X+003410Y+056660               S0      
317GND              VIA        MD0040PA00X+003440Y+009530               S0      
317GND              VIA        MD0040PA00X+003450Y+196320               S0      
317GND              VIA        MD0040PA00X+003500Y+193350               S0      
317GND              VIA        MD0040PA00X+003530Y+192530               S0      
317GND              VIA        MD0040PA00X+003600Y+183550               S0      
317GND              VIA        MD0040PA00X+003600Y+055400               S0      
317GND              VIA        MD0040PA00X+003600Y+073000               S0      
317GND              VIA        MD0040PA00X+003650Y+190050               S0      
317GND              VIA        MD0040PA00X+003670Y+176470               S0      
317GND              VIA        MD0040PA00X+003700Y+012400               S0      
317GND              VIA        MD0040PA00X+003750Y+111890               S0      
317GND              VIA        MD0040PA00X+003750Y+090750               S0      
317GND              VIA        MD0040PA00X+003750Y+091200               S0      
317GND              VIA        MD0040PA00X+003790Y+157000               S0      
317GND              VIA        MD0040PA00X+003800Y+133400               S0      
317GND              VIA        MD0040PA00X+003800Y+082000               S0      
317GND              VIA        MD0040PA00X+003800Y+083400               S0      
317GND              VIA        MD0040PA00X+003830Y+156180               S0      
317GND              VIA        MD0040PA00X+003830Y+157960               S0      
317GND              VIA        MD0040PA00X+003880Y+154170               S0      
317GND              VIA        MD0040PA00X+003950Y+123100               S0      
317GND              VIA        MD0040PA00X+003950Y+140790               S0      
317GND              VIA        MD0040PA00X+003970Y+184660               S0      
317GND              VIA        MD0040PA00X+003970Y+186970               S0      
317GND              VIA        MD0040PA00X+004000Y+113600               S0      
317GND              VIA        MD0040PA00X+004000Y+115600               S0      
317GND              VIA        MD0040PA00X+004000Y+127800               S0      
317GND              VIA        MD0040PA00X+004000Y+129800               S0      
317GND              VIA        MD0040PA00X+004000Y+074650               S0      
317GND              VIA        MD0040PA00X+004059Y+000600               S0      
317GND              VIA        MD0040PA00X+004090Y+090150               S0      
317GND              VIA        MD0040PA00X+004110Y+195750               S0      
317GND              VIA        MD0040PA00X+004200Y+124200               S0      
317GND              VIA        MD0040PA00X+004200Y+126600               S0      
317GND              VIA        MD0040PA00X+004200Y+129000               S0      
317GND              VIA        MD0040PA00X+004200Y+078800               S0      
317GND              VIA        MD0040PA00X+004200Y+080200               S0      
317GND              VIA        MD0040PA00X+004250Y+169950               S0      
317GND              VIA        MD0040PA00X+004260Y+144420               S0      
317GND              VIA        MD0040PA00X+004270Y+150000               S0      
317GND              VIA        MD0040PA00X+004300Y+002700               S0      
317GND              VIA        MD0040PA00X+004320Y+163480               S0      
317GND              VIA        MD0040PA00X+004330Y+151850               S0      
317GND              VIA        MD0040PA00X+004350Y+194500               S0      
317GND              VIA        MD0040PA00X+004400Y+119400               S0      
317GND              VIA        MD0040PA00X+004400Y+130600               S0      
317GND              VIA        MD0040PA00X+004400Y+132600               S0      
317GND              VIA        MD0040PA00X+004400Y+134000               S0      
317GND              VIA        MD0040PA00X+004400Y+078200               S0      
317GND              VIA        MD0040PA00X+004440Y+159210               S0      
317GND              VIA        MD0040PA00X+004440Y+182140               S0      
317GND              VIA        MD0040PA00X+004450Y+183350               S0      
317GND              VIA        MD0040PA00X+004460Y+172440               S0      
317GND              VIA        MD0040PA00X+004490Y+170680               S0      
317GND              VIA        MD0040PA00X+004490Y+174030               S0      
317GND              VIA        MD0040PA00X+000450Y+102950               S0      
317GND              VIA        MD0040PA00X+000450Y+010550               S0      
317GND              VIA        MD0040PA00X+000450Y+017050               S0      
317GND              VIA        MD0040PA00X+000450Y+193600               S0      
317GND              VIA        MD0040PA00X+000450Y+020250               S0      
317GND              VIA        MD0040PA00X+000450Y+083350               S0      
317GND              VIA        MD0040PA00X+000450Y+085750               S0      
317GND              VIA        MD0040PA00X+000450Y+091300               S0      
317GND              VIA        MD0040PA00X+000450Y+094150               S0      
317GND              VIA        MD0040PA00X+000450Y+097000               S0      
317GND              VIA        MD0040PA00X+000450Y+099700               S0      
317GND              VIA        MD0040PA00X+000459Y+101350               S0      
317GND              VIA        MD0040PA00X+000459Y+104150               S0      
317GND              VIA        MD0040PA00X+000459Y+116950               S0      
317GND              VIA        MD0040PA00X+000459Y+012050               S0      
317GND              VIA        MD0040PA00X+000459Y+138200               S0      
317GND              VIA        MD0040PA00X+000459Y+143550               S0      
317GND              VIA        MD0040PA00X+000459Y+160750               S0      
317GND              VIA        MD0040PA00X+000459Y+163200               S0      
317GND              VIA        MD0040PA00X+000459Y+169100               S0      
317GND              VIA        MD0040PA00X+000459Y+175100               S0      
317GND              VIA        MD0040PA00X+000459Y+177500               S0      
317GND              VIA        MD0040PA00X+000459Y+179950               S0      
317GND              VIA        MD0040PA00X+000459Y+182650               S0      
317GND              VIA        MD0040PA00X+000459Y+185000               S0      
317GND              VIA        MD0040PA00X+000459Y+018750               S0      
317GND              VIA        MD0040PA00X+000459Y+187850               S0      
317GND              VIA        MD0040PA00X+000459Y+190200               S0      
317GND              VIA        MD0040PA00X+000459Y+023400               S0      
317GND              VIA        MD0040PA00X+000459Y+039650               S0      
317GND              VIA        MD0040PA00X+000459Y+042100               S0      
317GND              VIA        MD0040PA00X+000459Y+062500               S0      
317GND              VIA        MD0040PA00X+000459Y+095400               S0      
317GND              VIA        MD0040PA00X+004510Y+193340               S0      
317GND              VIA        MD0040PA00X+004530Y+156360               S0      
317GND              VIA        MD0040PA00X+004540Y+152380               S0      
317GND              VIA        MD0040PA00X+004550Y+186500               S0      
317GND              VIA        MD0040PA00X+004560Y+082750               S0      
317GND              VIA        MD0040PA00X+004590Y+153280               S0      
317GND              VIA        MD0040PA00X+000460Y+148480               S0      
317GND              VIA        MD0040PA00X+004600Y+121800               S0      
317GND              VIA        MD0040PA00X+004600Y+192300               S0      
317GND              VIA        MD0040PA00X+004600Y+072600               S0      
317GND              VIA        MD0040PA00X+004600Y+083400               S0      
317GND              VIA        MD0040PA00X+004600Y+084800               S0      
317GND              VIA        MD0040PA00X+004650Y+148490               S0      
317GND              VIA        MD0040PA00X+004650Y+185020               S0      
317GND              VIA        MD0040PA00X+004660Y+154110               S0      
317GND              VIA        MD0040PA00X+004670Y+185770               S0      
317GND              VIA        MD0040PA00X+000470Y+167610               S0      
317GND              VIA        MD0040PA00X+000470Y+045820               S0      
317GND              VIA        MD0040PA00X+004700Y+087760               S0      
317GND              VIA        MD0040PA00X+004760Y+079680               S0      
317GND              VIA        MD0040PA00X+000480Y+146070               S0      
317GND              VIA        MD0040PA00X+000480Y+035620               S0      
317GND              VIA        MD0040PA00X+004800Y+081600               S0      
317GND              VIA        MD0040PA00X+004810Y+085340               S0      
317GND              VIA        MD0040PA00X+004890Y+139050               S0      
317GND              VIA        MD0040PA00X+000490Y+170800               S0      
317GND              VIA        MD0040PA00X+000490Y+032800               S0      
317GND              VIA        MD0040PA00X+004900Y+141330               S0      
317GND              VIA        MD0040PA00X+004900Y+001850               S0      
317GND              VIA        MD0040PA00X+004905Y+195175               S0      
317GND              VIA        MD0040PA00X+004910Y+144840               S0      
317GND              VIA        MD0040PA00X+004950Y+150500               S0      
317GND              VIA        MD0040PA00X+000500Y+013750               S0      
317GND              VIA        MD0040PA00X+000500Y+186410               S0      
317GND              VIA        MD0040PA00X+000500Y+022100               S0      
317GND              VIA        MD0040PA00X+000500Y+024750               S0      
317GND              VIA        MD0040PA00X+000500Y+040850               S0      
317GND              VIA        MD0040PA00X+000500Y+048650               S0      
317GND              VIA        MD0040PA00X+000500Y+049500               S0      
317GND              VIA        MD0040PA00X+000500Y+088350               S0      
317GND              VIA        MD0040PA00X+000509Y+107450               S0      
317GND              VIA        MD0040PA00X+000509Y+126850               S0      
317GND              VIA        MD0040PA00X+000509Y+192100               S0      
317GND              VIA        MD0040PA00X+000509Y+194450               S0      
317GND              VIA        MD0040PA00X+000509Y+027800               S0      
317GND              VIA        MD0040PA00X+000509Y+046950               S0      
317GND              VIA        MD0040PA00X+000509Y+060000               S0      
317GND              VIA        MD0040PA00X+000509Y+089750               S0      
317GND              VIA        MD0040PA00X+005000Y+124400               S0      
317GND              VIA        MD0040PA00X+005000Y+131800               S0      
317GND              VIA        MD0040PA00X+005000Y+071250               S0      
317GND              VIA        MD0040PA00X+005000Y+074900               S0      
317GND              VIA        MD0040PA00X+005010Y+126150               S0      
317GND              VIA        MD0040PA00X+005150Y+005300               S0      
317GND              VIA        MD0040PA00X+005170Y+013170               S0      
317GND              VIA        MD0040PA00X+005180Y+123160               S0      
317GND              VIA        MD0040PA00X+005190Y+014570               S0      
317GND              VIA        MD0040PA00X+005200Y+011560               S0      
317GND              VIA        MD0040PA00X+005200Y+129630               S0      
317GND              VIA        MD0040PA00X+005250Y+136850               S0      
317GND              VIA        MD0040PA00X+000530Y+120800               S0      
317GND              VIA        MD0040PA00X+000530Y+140940               S0      
317GND              VIA        MD0040PA00X+000530Y+150410               S0      
317GND              VIA        MD0040PA00X+000530Y+152210               S0      
317GND              VIA        MD0040PA00X+000530Y+154050               S0      
317GND              VIA        MD0040PA00X+000530Y+157620               S0      
317GND              VIA        MD0040PA00X+000530Y+165900               S0      
317GND              VIA        MD0040PA00X+000530Y+172350               S0      
317GND              VIA        MD0040PA00X+000530Y+034250               S0      
317GND              VIA        MD0040PA00X+000530Y+043450               S0      
317GND              VIA        MD0040PA00X+000530Y+044050               S0      
317GND              VIA        MD0040PA00X+000530Y+044450               S0      
317GND              VIA        MD0040PA00X+000530Y+066100               S0      
317GND              VIA        MD0040PA00X+000530Y+092600               S0      
317GND              VIA        MD0040PA00X+005300Y+175050               S0      
317GND              VIA        MD0040PA00X+005300Y+000500               S0      
317GND              VIA        MD0040PA00X+005310Y+143070               S0      
317GND              VIA        MD0040PA00X+005400Y+118400               S0      
317GND              VIA        MD0040PA00X+005400Y+133000               S0      
317GND              VIA        MD0040PA00X+005400Y+192850               S0      
317GND              VIA        MD0040PA00X+005450Y+188950               S0      
317GND              VIA        MD0040PA00X+000550Y+026950               S0      
317GND              VIA        MD0040PA00X+000550Y+029550               S0      
317GND              VIA        MD0040PA00X+000559Y+015350               S0      
317GND              VIA        MD0040PA00X+000559Y+031200               S0      
317GND              VIA        MD0040PA00X+000559Y+005350               S0      
317GND              VIA        MD0040PA00X+000559Y+068850               S0      
317GND              VIA        MD0040PA00X+000559Y+077800               S0      
317GND              VIA        MD0040PA00X+000559Y+084450               S0      
317GND              VIA        MD0040PA00X+000559Y+086900               S0      
317GND              VIA        MD0040PA00X+000559Y+008700               S0      
317GND              VIA        MD0040PA00X+000559Y+098450               S0      
317GND              VIA        MD0040PA00X+005530Y+195910               S0      
317GND              VIA        MD0040PA00X+005550Y+095550               S0      
317GND              VIA        MD0040PA00X+005550Y+096800               S0      
317GND              VIA        MD0040PA00X+005560Y+138170               S0      
317GND              VIA        MD0040PA00X+005650Y+176930               S0      
317GND              VIA        MD0040PA00X+005650Y+094000               S0      
317GND              VIA        MD0040PA00X+005670Y+140010               S0      
317GND              VIA        MD0040PA00X+005800Y+120600               S0      
317GND              VIA        MD0040PA00X+005800Y+122200               S0      
317GND              VIA        MD0040PA00X+005800Y+125000               S0      
317GND              VIA        MD0040PA00X+005800Y+127200               S0      
317GND              VIA        MD0040PA00X+005800Y+129200               S0      
317GND              VIA        MD0040PA00X+005800Y+131200               S0      
317GND              VIA        MD0040PA00X+005810Y+145930               S0      
317GND              VIA        MD0040PA00X+005880Y+141240               S0      
317GND              VIA        MD0040PA00X+000590Y+181410               S0      
317GND              VIA        MD0040PA00X+005900Y+144450               S0      
317GND              VIA        MD0040PA00X+005900Y+147200               S0      
317GND              VIA        MD0040PA00X+000600Y+105800               S0      
317GND              VIA        MD0040PA00X+000600Y+109600               S0      
317GND              VIA        MD0040PA00X+000600Y+111800               S0      
317GND              VIA        MD0040PA00X+000600Y+113800               S0      
317GND              VIA        MD0040PA00X+000600Y+115200               S0      
317GND              VIA        MD0040PA00X+000600Y+125200               S0      
317GND              VIA        MD0040PA00X+000600Y+131800               S0      
317GND              VIA        MD0040PA00X+000600Y+061200               S0      
317GND              VIA        MD0040PA00X+000600Y+064600               S0      
317GND              VIA        MD0040PA00X+000600Y+069800               S0      
317GND              VIA        MD0040PA00X+000600Y+070650               S0      
317GND              VIA        MD0040PA00X+000600Y+072200               S0      
317GND              VIA        MD0040PA00X+000600Y+073050               S0      
317GND              VIA        MD0040PA00X+000609Y+025700               S0      
317GND              VIA        MD0040PA00X+000609Y+081950               S0      
317GND              VIA        MD0040PA00X+006000Y+119400               S0      
317GND              VIA        MD0040PA00X+006060Y+142360               S0      
317GND              VIA        MD0040PA00X+006080Y+014770               S0      
317GND              VIA        MD0040PA00X+006090Y+139050               S0      
317GND              VIA        MD0040PA00X+006100Y+117300               S0      
317GND              VIA        MD0040PA00X+006100Y+136350               S0      
317GND              VIA        MD0040PA00X+006150Y+138000               S0      
317GND              VIA        MD0040PA00X+006150Y+192250               S0      
317GND              VIA        MD0040PA00X+006150Y+087650               S0      
317GND              VIA        MD0040PA00X+006150Y+093850               S0      
317GND              VIA        MD0040PA00X+006160Y+195470               S0      
317GND              VIA        MD0040PA00X+006250Y+086200               S0      
317GND              VIA        MD0040PA00X+006250Y+092450               S0      
317GND              VIA        MD0040PA00X+006260Y+014110               S0      
317GND              VIA        MD0040PA00X+006300Y+148230               S0      
317GND              VIA        MD0040PA00X+006310Y+011910               S0      
317GND              VIA        MD0040PA00X+006350Y+192800               S0      
317GND              VIA        MD0040PA00X+006350Y+196300               S0      
317GND              VIA        MD0040PA00X+006359Y+193550               S0      
317GND              VIA        MD0040PA00X+006359Y+002550               S0      
317GND              VIA        MD0040PA00X+006359Y+000700               S0      
317GND              VIA        MD0040PA00X+006400Y+001700               S0      
317GND              VIA        MD0040PA00X+006410Y+149540               S0      
317GND              VIA        MD0040PA00X+006450Y+004000               S0      
317GND              VIA        MD0040PA00X+000650Y+130200               S0      
317GND              VIA        MD0040PA00X+000650Y+196200               S0      
317GND              VIA        MD0040PA00X+000650Y+037500               S0      
317GND              VIA        MD0040PA00X+000650Y+079900               S0      
317GND              VIA        MD0040PA00X+006600Y+114950               S0      
317GND              VIA        MD0040PA00X+006650Y+143350               S0      
317GND              VIA        MD0040PA00X+006850Y+145460               S0      
317GND              VIA        MD0040PA00X+006880Y+141780               S0      
317GND              VIA        MD0040PA00X+006900Y+015300               S0      
317GND              VIA        MD0040PA00X+006910Y+069801               S0      
317GND              VIA        MD0040PA00X+006940Y+140290               S0      
317GND              VIA        MD0040PA00X+006950Y+093900               S0      
317GND              VIA        MD0040PA00X+006980Y+057420               S0      
317GND              VIA        MD0040PA00X+007000Y+091450               S0      
317GND              VIA        MD0040PA00X+007000Y+092550               S0      
317GND              VIA        MD0040PA00X+007040Y+144450               S0      
317GND              VIA        MD0040PA00X+007050Y+137850               S0      
317GND              VIA        MD0040PA00X+007100Y+013186               S0      
317GND              VIA        MD0040PA00X+007180Y+137390               S0      
317GND              VIA        MD0040PA00X+007180Y+070130               S0      
317GND              VIA        MD0040PA00X+007200Y+136000               S0      
317GND              VIA        MD0040PA00X+007230Y+146980               S0      
317GND              VIA        MD0040PA00X+007270Y+148050               S0      
317GND              VIA        MD0040PA00X+007290Y+139360               S0      
317GND              VIA        MD0040PA00X+007300Y+149120               S0      
317GND              VIA        MD0040PA00X+007350Y+014600               S0      
317GND              VIA        MD0040PA00X+007400Y+113200               S0      
317GND              VIA        MD0040PA00X+007400Y+004500               S0      
317GND              VIA        MD0040PA00X+007410Y+066940               S0      
317GND              VIA        MD0040PA00X+007450Y+146180               S0      
317GND              VIA        MD0040PA00X+007490Y+140880               S0      
317GND              VIA        MD0040PA00X+007494Y+053098               S0      
317GND              VIA        MD0040PA00X+000750Y+137650               S0      
317GND              VIA        MD0040PA00X+000750Y+164020               S0      
317GND              VIA        MD0040PA00X+007550Y+093650               S0      
317GND              VIA        MD0040PA00X+007560Y+142030               S0      
317GND              VIA        MD0040PA00X+007620Y+143070               S0      
317GND              VIA        MD0040PA00X+007640Y+099910               S0      
317GND              VIA        MD0040PA00X+007650Y+092700               S0      
317GND              VIA        MD0040PA00X+007700Y+144900               S0      
317GND              VIA        MD0040PA00X+007700Y+086300               S0      
317GND              VIA        MD0040PA00X+007700Y+087150               S0      
317GND              VIA        MD0040PA00X+007729Y+112973               S0      
317GND              VIA        MD0040PA00X+007750Y+090700               S0      
317GND              VIA        MD0040PA00X+007750Y+091700               S0      
317GND              VIA        MD0040PA00X+007760Y+084910               S0      
317GND              VIA        MD0040PA00X+007800Y+087850               S0      
317GND              VIA        MD0040PA00X+007830Y+083260               S0      
317GND              VIA        MD0040PA00X+007830Y+089390               S0      
317GND              VIA        MD0040PA00X+007900Y+143640               S0      
317GND              VIA        MD0040PA00X+007900Y+085700               S0      
317GND              VIA        MD0040PA00X+007904Y+114411               S0      
317GND              VIA        MD0040PA00X+007912Y+056570               S0      
317GND              VIA        MD0040PA00X+007946Y+057876               S0      
317GND              VIA        MD0040PA00X+000800Y+136800               S0      
317GND              VIA        MD0040PA00X+000800Y+067800               S0      
317GND              VIA        MD0040PA00X+008150Y+138200               S0      
317GND              VIA        MD0040PA00X+008150Y+140400               S0      
317GND              VIA        MD0040PA00X+008150Y+141650               S0      
317GND              VIA        MD0040PA00X+008150Y+083750               S0      
317GND              VIA        MD0040PA00X+008150Y+094000               S0      
317GND              VIA        MD0040PA00X+008200Y+080650               S0      
317GND              VIA        MD0040PA00X+008250Y+081400               S0      
317GND              VIA        MD0040PA00X+008340Y+087860               S0      
317GND              VIA        MD0040PA00X+008380Y+136590               S0      
317GND              VIA        MD0040PA00X+008380Y+139190               S0      
317GND              VIA        MD0040PA00X+008400Y+135200               S0      
317GND              VIA        MD0040PA00X+000850Y+123700               S0      
317GND              VIA        MD0040PA00X+000859Y+000650               S0      
317GND              VIA        MD0040PA00X+008500Y+004500               S0      
317GND              VIA        MD0040PA00X+008550Y+090300               S0      
317GND              VIA        MD0040PA00X+008550Y+091500               S0      
317GND              VIA        MD0040PA00X+008600Y+015200               S0      
317GND              VIA        MD0040PA00X+008650Y+093200               S0      
317GND              VIA        MD0040PA00X+008700Y+083950               S0      
317GND              VIA        MD0040PA00X+008700Y+099750               S0      
317GND              VIA        MD0040PA00X+008720Y+143190               S0      
317GND              VIA        MD0040PA00X+008730Y+143600               S0      
317GND              VIA        MD0040PA00X+008731Y+067680               S0      
317GND              VIA        MD0040PA00X+008760Y+058130               S0      
317GND              VIA        MD0040PA00X+008770Y+144650               S0      
317GND              VIA        MD0040PA00X+008850Y+094050               S0      
317GND              VIA        MD0040PA00X+008970Y+140970               S0      
317GND              VIA        MD0040PA00X+009000Y+089300               S0      
317GND              VIA        MD0040PA00X+009050Y+083150               S0      
317GND              VIA        MD0040PA00X+009080Y+133120               S0      
317GND              VIA        MD0040PA00X+009150Y+120000               S0      
317GND              VIA        MD0040PA00X+009150Y+122900               S0      
317GND              VIA        MD0040PA00X+009150Y+131450               S0      
317GND              VIA        MD0040PA00X+009200Y+121450               S0      
317GND              VIA        MD0040PA00X+009200Y+124150               S0      
317GND              VIA        MD0040PA00X+009200Y+125400               S0      
317GND              VIA        MD0040PA00X+009200Y+129550               S0      
317GND              VIA        MD0040PA00X+009300Y+092550               S0      
317GND              VIA        MD0040PA00X+009350Y+148270               S0      
317GND              VIA        MD0040PA00X+009360Y+140710               S0      
317GND              VIA        MD0040PA00X+009380Y+135390               S0      
317GND              VIA        MD0040PA00X+009380Y+137990               S0      
317GND              VIA        MD0040PA00X+009380Y+139320               S0      
317GND              VIA        MD0040PA00X+009400Y+118900               S0      
317GND              VIA        MD0040PA00X+009400Y+134000               S0      
317GND              VIA        MD0040PA00X+009400Y+136600               S0      
317GND              VIA        MD0040PA00X+009400Y+142780               S0      
317GND              VIA        MD0040PA00X+009400Y+091050               S0      
317GND              VIA        MD0040PA00X+000950Y+080400               S0      
317GND              VIA        MD0040PA00X+009500Y+012500               S0      
317GND              VIA        MD0040PA00X+009500Y+013400               S0      
317GND              VIA        MD0040PA00X+009500Y+014300               S0      
317GND              VIA        MD0040PA00X+009500Y+015500               S0      
317GND              VIA        MD0040PA00X+009500Y+004500               S0      
317GND              VIA        MD0040PA00X+009550Y+146800               S0      
317GND              VIA        MD0040PA00X+009550Y+084150               S0      
317GND              VIA        MD0040PA00X+009550Y+099900               S0      
317GND              VIA        MD0040PA00X+009605Y+090325               S0      
317GND              VIA        MD0040PA00X+009650Y+091650               S0      
317GND              VIA        MD0040PA00X+009700Y+150310               S0      
317GND              VIA        MD0040PA00X+009750Y+141200               S0      
317GND              VIA        MD0040PA00X+009780Y+132790               S0      
317GND              VIA        MD0040PA00X+009800Y+128200               S0      
317GND              VIA        MD0040PA00X+009800Y+042650               S0      
317GND              VIA        MD0040PA00X+009800Y+067433               S0      
317GND              VIA        MD0040PA00X+009900Y+126550               S0      
317GND              VIA        MD0040PA00X+009900Y+095300               S0      
317GND              VIA        MD0040PA00X+009900Y+069487               S0      
317GND              VIA        MD0040PA00X+009917Y+148579               S0      
317GND              VIA        MD0040PA00X+009950Y+129400               S0      
317GND              VIA        MD0040PA00X+009950Y+131000               S0      
317GND              VIA        MD0040PA00X+011302Y+145208               S0      
317GND              VIA        MD0040PA00X+011702Y+145200               S0      
317GND              VIA        MD0040PA00X+011712Y+144800               S0      
317GND              VIA        MD0040PA00X+011720Y+145607               S0      
317GND              VIA        MD0040PA00X+012134Y+145202               S0      
317GND              VIA        MD0040PA00X+013800Y+182400               S0      
317GND              VIA        MD0040PA00X+013850Y+172750               S0      
317GND              VIA        MD0040PA00X+013850Y+183950               S0      
317GND              VIA        MD0040PA00X+013900Y+169650               S0      
317GND              VIA        MD0040PA00X+013900Y+171250               S0      
317GND              VIA        MD0040PA00X+013900Y+180050               S0      
317GND              VIA        MD0040PA00X+013900Y+185100               S0      
317GND              VIA        MD0040PA00X+015150Y+185111               S0      
317GND              VIA        MD0040PA00X+015200Y+169711               S0      
317GND              VIA        MD0040PA00X+015200Y+171061               S0      
317GND              VIA        MD0040PA00X+015200Y+172561               S0      
317GND              VIA        MD0040PA00X+015200Y+179011               S0      
317GND              VIA        MD0040PA00X+015250Y+177111               S0      
317GND              VIA        MD0040PA00X+015550Y+179850               S0      
317GND              VIA        MD0040PA00X+015650Y+178200               S0      
317GND              VIA        MD0040PA00X+015850Y+170500               S0      
317GND              VIA        MD0040PA00X+015850Y+171650               S0      
317GND              VIA        MD0040PA00X+016150Y+185250               S0      
317GND              VIA        MD0040PA00X+016200Y+179000               S0      
317GND              VIA        MD0040PA00X+016250Y+177300               S0      
317GND              VIA        MD0040PA00X+016300Y+169700               S0      
317GND              VIA        MD0040PA00X+016650Y+179800               S0      
317GND              VIA        MD0040PA00X+016750Y+171600               S0      
317GND              VIA        MD0040PA00X+016850Y+170500               S0      
317GND              VIA        MD0040PA00X+016900Y+178150               S0      
317GND              VIA        MD0040PA00X+017277Y+179011               S0      
317GND              VIA        MD0040PA00X+017300Y+185261               S0      
317GND              VIA        MD0040PA00X+017327Y+177600               S0      
317GND              VIA        MD0040PA00X+017427Y+169711               S0      
317GND              VIA        MD0040PA00X+017900Y+179850               S0      
317GND              VIA        MD0040PA00X+018150Y+171650               S0      
317GND              VIA        MD0040PA00X+018200Y+170400               S0      
317GND              VIA        MD0040PA00X+018200Y+172600               S0      
317GND              VIA        MD0040PA00X+018310Y+183830               S0      
317GND              VIA        MD0040PA00X+018360Y+176510               S0      
317GND              VIA        MD0040PA00X+018450Y+169650               S0      
317GND              VIA        MD0040PA00X+018500Y+173850               S0      
317GND              VIA        MD0040PA00X+018500Y+185250               S0      
317GND              VIA        MD0040PA00X+018550Y+180450               S0      
317GND              VIA        MD0040PA00X+018600Y+179000               S0      
327P3V3                         D0040PA01X+010450Y+093351               S0      
317P3V3                         D0040PA01X+018047Y+063497               S0      
317P3V3                         D0040PA01X+015854Y+060408               S0      
317P3V3                         D0040PA01X+018202Y+061354               S0      
327P3V3                         D0040PA01X+017137Y+063482               S0      
317P3V3                         D0040PA01X+001860Y+164430               S0      
317P3V3                         D0040PA01X+011190Y+140820               S0      
317P3V3                         D0040PA01X+010750Y+140810               S0      
317P3V3                         D0040PA01X+003280Y+027230               S0      
317P3V3                         D0040PA01X+006030Y+028000               S0      
317P3V3                         D0040PA01X+006160Y+020790               S0      
317P3V3                         D0040PA01X+005780Y+021700               S0      
317P3V3                         D0040PA01X+006100Y+023660               S0      
317P3V3                         D0040PA01X+005740Y+067680               S0      
317P3V3                         D0040PA01X+006140Y+067680               S0      
317P3V3                         D0040PA01X+006300Y+026770               S0      
317P3V3                         D0040PA01X+006260Y+024580               S0      
317P3V3                         D0040PA01X+014380Y+100320               S0      
317P3V3                         D0040PA01X+015950Y+099770               S0      
317P3V3                         D0040PA01X+014500Y+094580               S0      
317P3V3                         D0040PA01X+016350Y+099770               S0      
317P3V3                         D0040PA01X+015700Y+094580               S0      
317P3V3                         D0040PA01X+015300Y+094580               S0      
317P3V3                         D0040PA01X+014900Y+094580               S0      
317P3V3                         D0040PA01X+015210Y+100320               S0      
317P3V3                         D0040PA01X+014790Y+100310               S0      
317P3V3                         D0040PA01X+009307Y+059407               S0      
317P3V3                         D0040PA01X+018037Y+064237               S0      
317P3V3                         D0040PA01X+013777Y+066207               S0      
317P3V3                         D0040PA01X+009520Y+066570               S0      
317P3V3                         D0040PA01X+008070Y+068640               S0      
317P3V3                         D0040PA01X+007856Y+069047               S0      
317P3V3                         D0040PA01X+003270Y+025690               S0      
317P3V3                         D0040PA01X+002910Y+032130               S0      
317P3V3                         D0040PA01X+002020Y+169280               S0      
317P3V3                         D0040PA01X+004340Y+089270               S0      
317P3V3                         D0040PA01X+002770Y+110600               S0      
317P3V3                         D0040PA01X+011050Y+093630               S0      
317P3V3                         D0040PA01X+011730Y+093630               S0      
317P3V3                         D0040PA01X+012167Y+093636               S0      
317P3V3                         D0040PA01X+010500Y+142030               S0      
317P3V3                         D0040PA01X+011800Y+142080               S0      
317P3V3                         D0040PA01X+008400Y+086150               S0      
317P3V3                         D0040PA01X+008400Y+085720               S0      
317P3V3                         D0040PA01X+008400Y+086570               S0      
317P3V3                         D0040PA01X+008400Y+085290               S0      
317P3V3                         D0040PA01X+008400Y+084410               S0      
317P3V3                         D0040PA01X+008400Y+084850               S0      
317P3V3                         D0040PA01X+002890Y+068530               S0      
317P3V3                         D0040PA01X+006720Y+070540               S0      
317P3V3                         D0040PA01X+002410Y+068530               S0      
317P3V3                         D0040PA01X+007220Y+070540               S0      
317P3V3                         D0040PA01X+013080Y+098140               S0      
317P3V3                         D0040PA01X+012990Y+098690               S0      
317P3V3                         D0040PA01X+007054Y+068831               S0      
317P3V3                         D0040PA01X+012347Y+067869               S0      
317P3V3                         D0040PA01X+012907Y+067869               S0      
317P3V3                         D0040PA01X+006564Y+068831               S0      
317P3V3                         D0040PA01X+010710Y+099080               S0      
317P3V3                         D0040PA01X+010710Y+098600               S0      
317P3V3                         D0040PA01X+008750Y+087285               S0      
317P3V3                         D0040PA01X+009230Y+087285               S0      
327P3V3                         D0040PA01X+011331Y+067742               S0      
327P3V3                         D0040PA01X+004275Y+069056               S0      
327P3V3                         D0040PA01X+005825Y+069056               S0      
327P3V3                         D0040PA01X+006688Y+068111               S0      
327P3V3                         D0040PA01X+011396Y+098520               S0      
327P3V3                         D0040PA01X+013734Y+098170               S0      
327P3V3                         D0040PA01X+010082Y+086850               S0      
317P3V3             VIA        MD0040PA04X+005200Y+086750               S0      
317P3V3             VIA        MD0040PA04X+005680Y+069100               S0      
317P3V3             VIA        MD0040PA04X+005680Y+083100               S0      
317P3V3             VIA        MD0040PA00X+001330Y+164430               S0      
317P3V3             VIA        MD0040PA00X+001330Y+168960               S0      
317P3V3             VIA        MD0040PA00X+002550Y+032120               S0      
317P3V3             VIA        MD0040PA00X+002645Y+027475               S0      
317P3V3             VIA        MD0040PA00X+004272Y+023399               S0      
317P3V3             VIA        MD0040PA00X+004960Y+088940               S0      
317P3V3             VIA        MD0040PA00X+005300Y+067350               S0      
317P3V3             VIA        MD0040PA00X+005440Y+021700               S0      
317P3V3             VIA        MD0040PA00X+005742Y+023297               S0      
317P3V3             VIA        MD0040PA00X+005750Y+084450               S0      
317P3V3             VIA        MD0040PA00X+005768Y+069764               S0      
317P3V3             VIA        MD0040PA00X+006500Y+023540               S0      
317P3V3             VIA        MD0040PA00X+006500Y+024150               S0      
317P3V3             VIA        MD0040PA00X+006520Y+020785               S0      
317P3V3             VIA        MD0040PA00X+006800Y+026800               S0      
317P3V3             VIA        MD0040PA00X+007060Y+025050               S0      
317P3V3             VIA        MD0040PA00X+010550Y+141500               S0      
317P3V3             VIA        MD0040PA00X+002805Y+025695               S0      
317P3V3             VIA        MD0040PA00X+003930Y+110580               S0      
317P3V3             VIA        MD0040PA00X+004100Y+093190               S0      
317P3V3             VIA        MD0040PA00X+005671Y+068107               S0      
317P3V3             VIA        MD0040PA00X+006450Y+116570               S0      
317P3V3             VIA        MD0040PA00X+008900Y+116740               S0      
327P12VU                        D0040PA01X+006964Y+036190               S0      
317P12VU                        D0040PA00X+008071Y+028693               S0      
317P12VU                        D0040PA00X+009071Y+028693               S0      
317P12VU                        D0040PA00X+010071Y+028693               S0      
317P12VU                        D0040PA00X+011071Y+028693               S0      
317P12VU                        D0040PA00X+008071Y+027693               S0      
317P12VU                        D0040PA00X+009071Y+027693               S0      
317P12VU                        D0040PA00X+010071Y+027693               S0      
317P12VU                        D0040PA00X+011071Y+027693               S0      
317P12VU                        D0040PA00X+008071Y+026693               S0      
317P12VU                        D0040PA00X+009071Y+026693               S0      
317P12VU                        D0040PA00X+010071Y+026693               S0      
317P12VU                        D0040PA00X+011071Y+026693               S0      
317P12VU                        D0040PA00X+008071Y+025693               S0      
317P12VU                        D0040PA00X+009071Y+025693               S0      
317P12VU                        D0040PA00X+010071Y+025693               S0      
317P12VU                        D0040PA00X+011071Y+025693               S0      
317P12VU                        D0040PA01X+007370Y+053990               S0      
317P12VU                        D0040PA01X+012890Y+058520               S0      
317P12VU                        D0040PA01X+004000Y+029430               S0      
327P12VU                        D0040PA01X+004770Y+039780               S0      
327P12VU                        D0040PA01X+004770Y+041830               S0      
327P12VU                        D0040PA01X+008110Y+041900               S0      
327P12VU                        D0040PA01X+008110Y+039850               S0      
327P12VU                        D0040PA01X+006900Y+044000               S0      
327P12VU                        D0040PA01X+007400Y+044000               S0      
327P12VU                        D0040PA01X+007900Y+044000               S0      
327P12VU                        D0040PA01X+009650Y+043950               S0      
327P12VU                        D0040PA01X+010150Y+043950               S0      
327P12VU                        D0040PA01X+010650Y+043950               S0      
327P12VU                        D0040PA01X+008343Y+054475               S0      
317P12VU            VIA        MD0040PA01X+006170Y+042190               S0      
317P12VU            VIA        MD0040PA01X+006240Y+043060               S0      
317P12VU            VIA        MD0040PA01X+006290Y+041290               S0      
317P12VU            VIA        MD0040PA01X+006320Y+038510               S0      
317P12VU            VIA        MD0040PA00X+012890Y+058050               S0      
317P12VU            VIA        MD0040PA00X+007780Y+054030               S0      
317P12VU            VIA        MD0040PA00X+010200Y+031200               S0      
317P12VU            VIA        MD0040PA00X+010400Y+030400               S0      
317P12VU            VIA        MD0040PA00X+010600Y+029600               S0      
317P12VU            VIA        MD0040PA00X+011400Y+029600               S0      
317P12VU            VIA        MD0040PA00X+005800Y+039000               S0      
317P12VU            VIA        MD0040PA00X+005800Y+040000               S0      
317P12VU            VIA        MD0040PA00X+005800Y+040800               S0      
317P12VU            VIA        MD0040PA00X+005800Y+041750               S0      
317P12VU            VIA        MD0040PA00X+005800Y+042600               S0      
317P12VU            VIA        MD0040PA00X+005810Y+043190               S0      
317P12VU            VIA        MD0040PA00X+006310Y+043454               S0      
317P12VU            VIA        MD0040PA00X+006600Y+039000               S0      
317P12VU            VIA        MD0040PA00X+006600Y+040000               S0      
317P12VU            VIA        MD0040PA00X+006600Y+040800               S0      
317P12VU            VIA        MD0040PA00X+006600Y+041800               S0      
317P12VU            VIA        MD0040PA00X+006600Y+042600               S0      
317P12VU            VIA        MD0040PA00X+006800Y+028600               S0      
317P12VU            VIA        MD0040PA00X+006800Y+029600               S0      
317P12VU            VIA        MD0040PA00X+006800Y+030400               S0      
317P12VU            VIA        MD0040PA00X+006800Y+031200               S0      
317P12VU            VIA        MD0040PA00X+006800Y+032000               S0      
317P12VU            VIA        MD0040PA00X+006850Y+043430               S0      
317P12VU            VIA        MD0040PA00X+007370Y+042300               S0      
317P12VU            VIA        MD0040PA00X+007400Y+039000               S0      
317P12VU            VIA        MD0040PA00X+007400Y+040000               S0      
317P12VU            VIA        MD0040PA00X+007400Y+040800               S0      
317P12VU            VIA        MD0040PA00X+007400Y+041800               S0      
317P12VU            VIA        MD0040PA00X+007600Y+029600               S0      
317P12VU            VIA        MD0040PA00X+008100Y+041050               S0      
317P12VU            VIA        MD0040PA00X+008450Y+043300               S0      
317P12VU            VIA        MD0040PA00X+008600Y+029600               S0      
317P12VU            VIA        MD0040PA00X+008640Y+041050               S0      
317P12VU            VIA        MD0040PA00X+008850Y+042650               S0      
317P12VU            VIA        MD0040PA00X+009190Y+041050               S0      
317P12VU            VIA        MD0040PA00X+009400Y+030400               S0      
317P12VU            VIA        MD0040PA00X+009400Y+031200               S0      
317P12VU            VIA        MD0040PA00X+009400Y+032000               S0      
317P12VU            VIA        MD0040PA00X+009600Y+029600               S0      
327P12VL                        D0040PA01X+014047Y+036180               S0      
317P12VL                        D0040PA00X+014961Y+028693               S0      
317P12VL                        D0040PA00X+015961Y+028693               S0      
317P12VL                        D0040PA00X+016961Y+028693               S0      
317P12VL                        D0040PA00X+017961Y+028693               S0      
317P12VL                        D0040PA00X+014961Y+027693               S0      
317P12VL                        D0040PA00X+015961Y+027693               S0      
317P12VL                        D0040PA00X+016961Y+027693               S0      
317P12VL                        D0040PA00X+017961Y+027693               S0      
317P12VL                        D0040PA00X+014961Y+026693               S0      
317P12VL                        D0040PA00X+015961Y+026693               S0      
317P12VL                        D0040PA00X+016961Y+026693               S0      
317P12VL                        D0040PA00X+017961Y+026693               S0      
317P12VL                        D0040PA00X+014961Y+025693               S0      
317P12VL                        D0040PA00X+015961Y+025693               S0      
317P12VL                        D0040PA00X+016961Y+025693               S0      
317P12VL                        D0040PA00X+017961Y+025693               S0      
317P12VL                        D0040PA01X+013678Y+053967               S0      
317P12VL                        D0040PA01X+011680Y+058520               S0      
317P12VL                        D0040PA01X+011690Y+038010               S0      
327P12VL                        D0040PA01X+016060Y+037690               S0      
327P12VL                        D0040PA01X+016040Y+035670               S0      
327P12VL                        D0040PA01X+016050Y+041840               S0      
327P12VL                        D0040PA01X+016050Y+039790               S0      
327P12VL                        D0040PA01X+016900Y+043950               S0      
327P12VL                        D0040PA01X+017400Y+043950               S0      
327P12VL                        D0040PA01X+017900Y+043950               S0      
327P12VL                        D0040PA01X+014100Y+043950               S0      
327P12VL                        D0040PA01X+014600Y+043950               S0      
327P12VL                        D0040PA01X+015100Y+043950               S0      
327P12VL                        D0040PA01X+014723Y+054295               S0      
317P12VL            VIA        MD0040PA01X+012250Y+042900               S0      
317P12VL            VIA        MD0040PA01X+012510Y+040890               S0      
317P12VL            VIA        MD0040PA01X+014340Y+040820               S0      
317P12VL            VIA        MD0040PA00X+012230Y+057500               S0      
317P12VL            VIA        MD0040PA00X+013250Y+053962               S0      
317P12VL            VIA        MD0040PA00X+013550Y+044100               S0      
317P12VL            VIA        MD0040PA00X+011800Y+038600               S0      
317P12VL            VIA        MD0040PA00X+011800Y+039600               S0      
317P12VL            VIA        MD0040PA00X+011800Y+040400               S0      
317P12VL            VIA        MD0040PA00X+011800Y+041400               S0      
317P12VL            VIA        MD0040PA00X+011800Y+042400               S0      
317P12VL            VIA        MD0040PA00X+013000Y+043200               S0      
317P12VL            VIA        MD0040PA00X+013400Y+038600               S0      
317P12VL            VIA        MD0040PA00X+013400Y+039600               S0      
317P12VL            VIA        MD0040PA00X+013400Y+040450               S0      
317P12VL            VIA        MD0040PA00X+013400Y+041400               S0      
317P12VL            VIA        MD0040PA00X+013400Y+042400               S0      
317P12VL            VIA        MD0040PA00X+014200Y+029100               S0      
317P12VL            VIA        MD0040PA00X+014200Y+043200               S0      
317P12VL            VIA        MD0040PA00X+014330Y+034340               S0      
317P12VL            VIA        MD0040PA00X+014340Y+031870               S0      
317P12VL            VIA        MD0040PA00X+014550Y+042700               S0      
317P12VL            VIA        MD0040PA00X+015000Y+038600               S0      
317P12VL            VIA        MD0040PA00X+015000Y+039600               S0      
317P12VL            VIA        MD0040PA00X+015000Y+040400               S0      
317P12VL            VIA        MD0040PA00X+015000Y+041400               S0      
317P12VL            VIA        MD0040PA00X+015000Y+042400               S0      
317P12VL            VIA        MD0040PA00X+015130Y+029820               S0      
317P12VL            VIA        MD0040PA00X+016200Y+029600               S0      
317P12VL            VIA        MD0040PA00X+016200Y+043200               S0      
317P12VL            VIA        MD0040PA00X+016400Y+031600               S0      
317P12VL            VIA        MD0040PA00X+016600Y+030200               S0      
317P12VL            VIA        MD0040PA00X+017200Y+029600               S0      
317P12VL            VIA        MD0040PA00X+017200Y+031000               S0      
317P12VL            VIA        MD0040PA00X+017400Y+031600               S0      
317P12VL            VIA        MD0040PA00X+017450Y+043200               S0      
317P12VL            VIA        MD0040PA00X+017600Y+030200               S0      
317P12VL            VIA        MD0040PA00X+018200Y+029600               S0      
317P12VL            VIA        MD0040PA00X+018200Y+031000               S0      
317P12VL            VIA        MD0040PA00X+018400Y+030300               S0      
317P12V_AUX                     D0040PA01X+009646Y+177343               S0      
327P12V_AUX                     D0040PA01X+006064Y+168050               S0      
327P12V_AUX                     D0040PA01X+015775Y+161970               S0      
327P12V_AUX                     D0040PA01X+013025Y+161970               S0      
327P12V_AUX                     D0040PA01X+010175Y+161970               S0      
327P12V_AUX                     D0040PA01X+007125Y+161970               S0      
327P12V_AUX                     D0040PA01X+013540Y+073005               S0      
317P12V_AUX                     D0040PA01X+015210Y+141500               S0      
317P12V_AUX                     D0040PA01X+015210Y+141920               S0      
317P12V_AUX                     D0040PA01X+015210Y+142340               S0      
317P12V_AUX                     D0040PA01X+017770Y+062430               S0      
317P12V_AUX                     D0040PA01X+008350Y+146520               S0      
317P12V_AUX                     D0040PA01X+008430Y+148400               S0      
317P12V_AUX                     D0040PA01X+014360Y+145330               S0      
317P12V_AUX                     D0040PA01X+015233Y+142768               S0      
327P12V_AUX                     D0040PA01X+016700Y+146530               S0      
317P12V_AUX                     D0040PA01X+018230Y+164800               S0      
317P12V_AUX                     D0040PA01X+018230Y+165270               S0      
317P12V_AUX                     D0040PA01X+012490Y+072820               S0      
327P12V_AUX                     D0040PA01X+018070Y+164100               S0      
317P12V_AUX                     D0040PA01X+010750Y+149020               S0      
317P12V_AUX                     D0040PA00X+009646Y+174784               S0      
317P12V_AUX                     D0040PA00X+009646Y+182303               S0      
317P12V_AUX         VIA        MD0040PA04X+007100Y+186450               S0      
317P12V_AUX         VIA        MD0040PA04X+007650Y+149850               S0      
317P12V_AUX         VIA        MD0040PA01X+013650Y+165100               S0      
317P12V_AUX         VIA        MD0040PA01X+005950Y+162750               S0      
317P12V_AUX         VIA        MD0040PA01X+006150Y+171650               S0      
317P12V_AUX         VIA        MD0040PA01X+006230Y+164130               S0      
317P12V_AUX         VIA        MD0040PA01X+008400Y+186960               S0      
317P12V_AUX         VIA        MD0040PA00X+011275Y+149125               S0      
317P12V_AUX         VIA        MD0040PA00X+013990Y+141510               S0      
317P12V_AUX         VIA        MD0040PA00X+015850Y+146650               S0      
317P12V_AUX         VIA        MD0040PA00X+015860Y+075260               S0      
317P12V_AUX         VIA        MD0040PA00X+017420Y+062820               S0      
317P12V_AUX         VIA        MD0040PA00X+010300Y+168500               S0      
317P12V_AUX         VIA        MD0040PA00X+010600Y+163400               S0      
317P12V_AUX         VIA        MD0040PA00X+010650Y+186250               S0      
317P12V_AUX         VIA        MD0040PA00X+010700Y+165950               S0      
317P12V_AUX         VIA        MD0040PA00X+010700Y+166900               S0      
317P12V_AUX         VIA        MD0040PA00X+010750Y+167900               S0      
317P12V_AUX         VIA        MD0040PA00X+010800Y+164600               S0      
317P12V_AUX         VIA        MD0040PA00X+011250Y+168500               S0      
317P12V_AUX         VIA        MD0040PA00X+011450Y+186250               S0      
317P12V_AUX         VIA        MD0040PA00X+011700Y+163350               S0      
317P12V_AUX         VIA        MD0040PA00X+011750Y+165950               S0      
317P12V_AUX         VIA        MD0040PA00X+011750Y+166900               S0      
317P12V_AUX         VIA        MD0040PA00X+011750Y+167900               S0      
317P12V_AUX         VIA        MD0040PA00X+011800Y+164600               S0      
317P12V_AUX         VIA        MD0040PA00X+012200Y+168550               S0      
317P12V_AUX         VIA        MD0040PA00X+012250Y+186250               S0      
317P12V_AUX         VIA        MD0040PA00X+012500Y+167900               S0      
317P12V_AUX         VIA        MD0040PA00X+012700Y+164600               S0      
317P12V_AUX         VIA        MD0040PA00X+012750Y+163300               S0      
317P12V_AUX         VIA        MD0040PA00X+012750Y+165950               S0      
317P12V_AUX         VIA        MD0040PA00X+012750Y+166900               S0      
317P12V_AUX         VIA        MD0040PA00X+013750Y+165950               S0      
317P12V_AUX         VIA        MD0040PA00X+013800Y+163400               S0      
317P12V_AUX         VIA        MD0040PA00X+013800Y+164600               S0      
317P12V_AUX         VIA        MD0040PA00X+014800Y+164600               S0      
317P12V_AUX         VIA        MD0040PA00X+014850Y+166000               S0      
317P12V_AUX         VIA        MD0040PA00X+014900Y+163250               S0      
317P12V_AUX         VIA        MD0040PA00X+015250Y+145600               S0      
317P12V_AUX         VIA        MD0040PA00X+015800Y+164600               S0      
317P12V_AUX         VIA        MD0040PA00X+015900Y+163250               S0      
317P12V_AUX         VIA        MD0040PA00X+015900Y+165950               S0      
317P12V_AUX         VIA        MD0040PA00X+016600Y+164600               S0      
317P12V_AUX         VIA        MD0040PA00X+016750Y+163250               S0      
317P12V_AUX         VIA        MD0040PA00X+017000Y+165950               S0      
317P12V_AUX         VIA        MD0040PA00X+017600Y+163200               S0      
317P12V_AUX         VIA        MD0040PA00X+017600Y+164600               S0      
317P12V_AUX         VIA        MD0040PA00X+017800Y+165950               S0      
317P12V_AUX         VIA        MD0040PA00X+005350Y+165900               S0      
317P12V_AUX         VIA        MD0040PA00X+005400Y+164650               S0      
317P12V_AUX         VIA        MD0040PA00X+005500Y+163400               S0      
317P12V_AUX         VIA        MD0040PA00X+005550Y+172350               S0      
317P12V_AUX         VIA        MD0040PA00X+005550Y+173550               S0      
317P12V_AUX         VIA        MD0040PA00X+005600Y+169500               S0      
317P12V_AUX         VIA        MD0040PA00X+005600Y+170450               S0      
317P12V_AUX         VIA        MD0040PA00X+005600Y+171250               S0      
317P12V_AUX         VIA        MD0040PA00X+005950Y+166700               S0      
317P12V_AUX         VIA        MD0040PA00X+006000Y+173000               S0      
317P12V_AUX         VIA        MD0040PA00X+006250Y+169150               S0      
317P12V_AUX         VIA        MD0040PA00X+006250Y+170000               S0      
317P12V_AUX         VIA        MD0040PA00X+006250Y+170900               S0      
317P12V_AUX         VIA        MD0040PA00X+006350Y+185600               S0      
317P12V_AUX         VIA        MD0040PA00X+006350Y+186300               S0      
317P12V_AUX         VIA        MD0040PA00X+006400Y+163400               S0      
317P12V_AUX         VIA        MD0040PA00X+006400Y+183400               S0      
317P12V_AUX         VIA        MD0040PA00X+006400Y+184450               S0      
317P12V_AUX         VIA        MD0040PA00X+006450Y+164600               S0      
317P12V_AUX         VIA        MD0040PA00X+006450Y+165850               S0      
317P12V_AUX         VIA        MD0040PA00X+006450Y+175850               S0      
317P12V_AUX         VIA        MD0040PA00X+006450Y+180150               S0      
317P12V_AUX         VIA        MD0040PA00X+006450Y+181200               S0      
317P12V_AUX         VIA        MD0040PA00X+006450Y+182150               S0      
317P12V_AUX         VIA        MD0040PA00X+006500Y+172400               S0      
317P12V_AUX         VIA        MD0040PA00X+006500Y+173500               S0      
317P12V_AUX         VIA        MD0040PA00X+006500Y+174250               S0      
317P12V_AUX         VIA        MD0040PA00X+006500Y+174900               S0      
317P12V_AUX         VIA        MD0040PA00X+006500Y+176800               S0      
317P12V_AUX         VIA        MD0040PA00X+006500Y+179000               S0      
317P12V_AUX         VIA        MD0040PA00X+006900Y+168450               S0      
317P12V_AUX         VIA        MD0040PA00X+007000Y+166800               S0      
317P12V_AUX         VIA        MD0040PA00X+007550Y+165950               S0      
317P12V_AUX         VIA        MD0040PA00X+007550Y+167900               S0      
317P12V_AUX         VIA        MD0040PA00X+007600Y+163400               S0      
317P12V_AUX         VIA        MD0040PA00X+007600Y+164600               S0      
317P12V_AUX         VIA        MD0040PA00X+008050Y+168450               S0      
317P12V_AUX         VIA        MD0040PA00X+008350Y+146950               S0      
317P12V_AUX         VIA        MD0040PA00X+008500Y+149000               S0      
317P12V_AUX         VIA        MD0040PA00X+008600Y+163400               S0      
317P12V_AUX         VIA        MD0040PA00X+008600Y+164600               S0      
317P12V_AUX         VIA        MD0040PA00X+008600Y+165950               S0      
317P12V_AUX         VIA        MD0040PA00X+008600Y+166900               S0      
317P12V_AUX         VIA        MD0040PA00X+008600Y+167900               S0      
317P12V_AUX         VIA        MD0040PA00X+009100Y+168500               S0      
317P12V_AUX         VIA        MD0040PA00X+009600Y+164600               S0      
317P12V_AUX         VIA        MD0040PA00X+009650Y+163400               S0      
317P12V_AUX         VIA        MD0040PA00X+009700Y+165950               S0      
317P12V_AUX         VIA        MD0040PA00X+009700Y+166900               S0      
317P12V_AUX         VIA        MD0040PA00X+009750Y+167950               S0      
317P12V_AUX         VIA        MD0040PA00X+009950Y+186250               S0      
317P12V_AUX         VIA        MD0040PA00X+010777Y+178911               S0      
317P12V_AUX         VIA        MD0040PA00X+010827Y+177730               S0      
317P12V_AUX         VIA        MD0040PA00X+010850Y+172700               S0      
317P12V_AUX         VIA        MD0040PA00X+010850Y+185161               S0      
317P12V_AUX         VIA        MD0040PA00X+010950Y+169900               S0      
317P12V_AUX         VIA        MD0040PA00X+010950Y+171950               S0      
317P12V_AUX         VIA        MD0040PA00X+011000Y+170950               S0      
317P12V_AUX         VIA        MD0040PA00X+011050Y+180100               S0      
317P12V_AUX         VIA        MD0040PA00X+011150Y+176850               S0      
317P12V_AUX         VIA        MD0040PA00X+011400Y+184350               S0      
317P12V_AUX         VIA        MD0040PA00X+011750Y+173200               S0      
317P12V_AUX         VIA        MD0040PA00X+011950Y+169661               S0      
317P12V_AUX         VIA        MD0040PA00X+011950Y+171011               S0      
317P12V_AUX         VIA        MD0040PA00X+011950Y+172511               S0      
317P12V_AUX         VIA        MD0040PA00X+011950Y+174711               S0      
317P12V_AUX         VIA        MD0040PA00X+011950Y+176000               S0      
317P12V_AUX         VIA        MD0040PA00X+011950Y+179650               S0      
317P12V_AUX         VIA        MD0040PA00X+012000Y+181150               S0      
317P12V_AUX         VIA        MD0040PA00X+012050Y+183650               S0      
317P12V_AUX         VIA        MD0040PA00X+012050Y+185050               S0      
317P12V_AUX         VIA        MD0040PA00X+007150Y+176000               S0      
317P12V_AUX         VIA        MD0040PA00X+007200Y+179800               S0      
317P12V_AUX         VIA        MD0040PA00X+007250Y+169900               S0      
317P12V_AUX         VIA        MD0040PA00X+007250Y+171700               S0      
317P12V_AUX         VIA        MD0040PA00X+007250Y+173300               S0      
317P12V_AUX         VIA        MD0040PA00X+007250Y+183000               S0      
317P12V_AUX         VIA        MD0040PA00X+007300Y+181300               S0      
317P12V_AUX         VIA        MD0040PA00X+007300Y+184700               S0      
317P12V_AUX         VIA        MD0040PA00X+007550Y+183850               S0      
317P12V_AUX         VIA        MD0040PA00X+007900Y+176650               S0      
317P12V_AUX         VIA        MD0040PA00X+008100Y+180200               S0      
317P12V_AUX         VIA        MD0040PA00X+008510Y+184450               S0      
317P12V_AUX         VIA        MD0040PA00X+008570Y+185230               S0      
317P12V_AUX         VIA        MD0040PA00X+008650Y+170011               S0      
317P12V_AUX         VIA        MD0040PA00X+008650Y+171361               S0      
317P12V_AUX         VIA        MD0040PA00X+008650Y+172600               S0      
317P12V_AUX         VIA        MD0040PA00X+008650Y+179311               S0      
317P12V_AUX         VIA        MD0040PA00X+008700Y+177411               S0      
317P12V_AUX         VIA        MD0040PA00X+008850Y+178500               S0      
317P12V_AUX         VIA        MD0040PA00X+009700Y+185050               S0      
317P12V_AUX         VIA        MD0040PA00X+009750Y+177550               S0      
317P12V_AUX         VIA        MD0040PA00X+009750Y+179600               S0      
317P12V_AUX         VIA        MD0040PA00X+009800Y+178600               S0      
317P12V_AUX         VIA        MD0040PA00X+009850Y+169650               S0      
317P12V_AUX         VIA        MD0040PA00X+009850Y+171700               S0      
317P12V_AUX         VIA        MD0040PA00X+009900Y+170700               S0      
317D_LATCH_PRE#                 D0040PA01X+005690Y+018730               S0      
317D_LATCH_PRE#                 D0040PA01X+005660Y+019160               S0      
317D_LATCH_PRE#                 D0040PA01X+015850Y+070270               S0      
317D_LATCH_PRE#                 D0040PA01X+016330Y+070210               S0      
327D_LATCH_PRE#                 D0040PA01X+016350Y+071010               S0      
317D_LATCH_PRE#     VIA        MD0040PA01X+015850Y+069500               S0      
317D_LATCH_PRE#     VIA        MD0040PA00X+016150Y+069170               S0      
317D_LATCH_PRE#     VIA        MD0040PA00X+005340Y+019130               S0      
317P3V3_AUX                     D0040PA01X+015050Y+069920               S0      
327P3V3_AUX                     D0040PA01X+013928Y+072255               S0      
317P3V3_AUX                     D0040PA01X+015850Y+069930               S0      
317P3V3_AUX                     D0040PA01X+014950Y+070830               S0      
317P3V3_AUX                     D0040PA01X+016770Y+069620               S0      
317P3V3_AUX                     D0040PA01X+015450Y+069930               S0      
327P3V3_AUX                     D0040PA01X+014700Y+072100               S0      
327P3V3_AUX                     D0040PA01X+016606Y+073230               S0      
327P3V3_AUX                     D0040PA01X+015838Y+073230               S0      
327P3V3_AUX                     D0040PA01X+015583Y+073230               S0      
317P3V3_AUX         VIA        MD0040PA01X+014200Y+070100               S0      
317P3V3_AUX         VIA        MD0040PA01X+017300Y+069100               S0      
327NNAME00000                   D0040PA01X+014257Y+142977               S0      
317NNAME00000                   D0040PA01X+015730Y+145800               S0      
317NNAME00000                   D0040PA01X+016030Y+146250               S0      
317NNAME00000                   D0040PA01X+015138Y+144475               S0      
317NNAME00000       VIA        MD0040PA04X+015600Y+144750               S0      
317NNAME00000       VIA        MD0040PA00X+015150Y+143850               S0      
317NNAME00000       VIA        MD0040PA00X+015750Y+145480               S0      
317TEMP_ALM#_IN_D               D0040PA01X+014430Y+069550               S0      
327TEMP_ALM#_IN_D               D0040PA01X+014550Y+068975               S0      
317TEMP_ALM#_IN_D               D0040PA01X+015450Y+070270               S0      
327TEMP_ALM#_IN_D               D0040PA01X+016094Y+071010               S0      
317TEMP_ALM#_IN_D   VIA        MD0040PA04X+015200Y+069569               S0      
317TEMP_ALM#_IN_D   VIA        MD0040PA00X+015070Y+069170               S0      
317TEMP_ALM#_IN_D   VIA        MD0040PA00X+015319Y+070589               S0      
327P12V                         D0040PA01X+008555Y+010300               S0      
327P12V                         D0040PA01X+005600Y+062345               S0      
327P12V                         D0040PA01X+009015Y+077670               S0      
327P12V                         D0040PA01X+007595Y+106970               S0      
327P12V                         D0040PA01X+010510Y+113555               S0      
327P12V                         D0040PA01X+008010Y+189195               S0      
317P12V                         D0040PA01X+005710Y+097930               S0      
327P12V                         D0040PA01X+015784Y+150770               S0      
327P12V                         D0040PA01X+001620Y+165710               S0      
327P12V                         D0040PA01X+001580Y+169920               S0      
327P12V                         D0040PA01X+003900Y+102250               S0      
327P12V                         D0040PA01X+004990Y+088380               S0      
327P12V                         D0040PA01X+002530Y+032850               S0      
327P12V                         D0040PA01X+003890Y+024690               S0      
327P12V                         D0040PA01X+015800Y+049095               S0      
327P12V                         D0040PA01X+017600Y+049095               S0      
327P12V                         D0040PA01X+009000Y+049145               S0      
327P12V                         D0040PA01X+007200Y+049145               S0      
317P12V                         D0040PA01X+015800Y+057860               S0      
317P12V                         D0040PA01X+015620Y+058700               S0      
317P12V                         D0040PA01X+007070Y+006350               S0      
317P12V                         D0040PA01X+006740Y+006760               S0      
317P12V                         D0040PA01X+006800Y+005310               S0      
317P12V                         D0040PA01X+009610Y+053050               S0      
317P12V                         D0040PA01X+017060Y+052910               S0      
317P12V                         D0040PA01X+007580Y+102090               S0      
317P12V                         D0040PA01X+006870Y+073000               S0      
317P12V                         D0040PA01X+007570Y+102540               S0      
317P12V                         D0040PA01X+008970Y+073340               S0      
317P12V                         D0040PA01X+007210Y+100430               S0      
317P12V                         D0040PA01X+009120Y+070790               S0      
317P12V                         D0040PA01X+003340Y+057080               S0      
317P12V                         D0040PA01X+003900Y+057790               S0      
317P12V                         D0040PA01X+006100Y+057720               S0      
317P12V                         D0040PA01X+014850Y+147070               S0      
317P12V                         D0040PA01X+014390Y+146240               S0      
317P12V                         D0040PA01X+014390Y+146640               S0      
317P12V                         D0040PA01X+007220Y+117510               S0      
317P12V                         D0040PA01X+006350Y+112040               S0      
317P12V                         D0040PA01X+008140Y+112270               S0      
317P12V                         D0040PA01X+003410Y+177440               S0      
317P12V                         D0040PA01X+003840Y+178820               S0      
317P12V                         D0040PA01X+004830Y+175230               S0      
317P12V                         D0040PA01X+010390Y+048220               S0      
317P12V                         D0040PA01X+014670Y+048230               S0      
317P12V                         D0040PA01X+014180Y+188370               S0      
317P12V                         D0040PA01X+014185Y+187870               S0      
317P12V                         D0040PA01X+005220Y+024450               S0      
317P12V                         D0040PA01X+004750Y+024450               S0      
317P12V                         D0040PA01X+005820Y+065760               S0      
317P12V                         D0040PA01X+005820Y+066230               S0      
317P12V                         D0040PA01X+009970Y+105370               S0      
317P12V                         D0040PA01X+009970Y+105840               S0      
317P12V                         D0040PA01X+011020Y+076410               S0      
317P12V                         D0040PA01X+011020Y+076910               S0      
317P12V                         D0040PA01X+014900Y+111695               S0      
317P12V                         D0040PA01X+014430Y+111690               S0      
327P12V                         D0040PA01X+011310Y+008850               S0      
327P12V                         D0040PA01X+006140Y+155150               S0      
327P12V                         D0040PA01X+007890Y+152350               S0      
327P12V                         D0040PA01X+009840Y+079840               S0      
327P12V                         D0040PA01X+008850Y+109060               S0      
327P12V                         D0040PA01X+012430Y+188350               S0      
327P12V                         D0040PA01X+016020Y+155160               S0      
327P12V                         D0040PA01X+016010Y+153150               S0      
327P12V                         D0040PA01X+014580Y+112650               S0      
327P12V                         D0040PA01X+004390Y+066700               S0      
327P12V                         D0040PA01X+006040Y+157560               S0      
327P12V                         D0040PA01X+006540Y+157560               S0      
327P12V                         D0040PA01X+007040Y+157560               S0      
327P12V                         D0040PA01X+009350Y+157550               S0      
327P12V                         D0040PA01X+009850Y+157550               S0      
327P12V                         D0040PA01X+010350Y+157550               S0      
327P12V                         D0040PA01X+012850Y+157550               S0      
327P12V                         D0040PA01X+013350Y+157550               S0      
327P12V                         D0040PA01X+013850Y+157550               S0      
327P12V                         D0040PA01X+016250Y+157550               S0      
327P12V                         D0040PA01X+016750Y+157550               S0      
327P12V                         D0040PA01X+017250Y+157550               S0      
327P12V                         D0040PA01X+010915Y+006850               S0      
327P12V                         D0040PA01X+009125Y+005450               S0      
327P12V                         D0040PA01X+007775Y+103210               S0      
327P12V                         D0040PA01X+009465Y+074040               S0      
327P12V                         D0040PA01X+007345Y+101180               S0      
327P12V                         D0040PA01X+009515Y+071540               S0      
327P12V                         D0040PA01X+005835Y+059300               S0      
327P12V                         D0040PA01X+005835Y+058400               S0      
327P12V                         D0040PA01X+008850Y+112295               S0      
327P12V                         D0040PA01X+003465Y+178100               S0      
327P12V                         D0040PA01X+004160Y+175425               S0      
327P12V                         D0040PA01X+007020Y+112505               S0      
327P12V                         D0040PA01X+009900Y+008620               S0      
327P12V                         D0040PA01X+009940Y+075790               S0      
327P12V                         D0040PA01X+009050Y+105010               S0      
327P12V                         D0040PA01X+009850Y+188320               S0      
327P12V                         D0040PA01X+007340Y+063350               S0      
327P12V                         D0040PA01X+012210Y+112530               S0      
317P12V             VIA        MD0040PA01X+010550Y+073200               S0      
317P12V             VIA        MD0040PA01X+010900Y+080950               S0      
317P12V             VIA        MD0040PA01X+011500Y+048610               S0      
317P12V             VIA        MD0040PA01X+011750Y+151950               S0      
317P12V             VIA        MD0040PA01X+013700Y+187750               S0      
317P12V             VIA        MD0040PA01X+013986Y+188946               S0      
317P12V             VIA        MD0040PA01X+014900Y+052250               S0      
317P12V             VIA        MD0040PA01X+017850Y+126850               S0      
317P12V             VIA        MD0040PA01X+018600Y+113300               S0      
317P12V             VIA        MD0040PA01X+018900Y+143200               S0      
317P12V             VIA        MD0040PA01X+019750Y+048150               S0      
317P12V             VIA        MD0040PA01X+004334Y+065015               S0      
317P12V             VIA        MD0040PA01X+004967Y+064293               S0      
317P12V             VIA        MD0040PA01X+006600Y+051050               S0      
317P12V             VIA        MD0040PA01X+008550Y+100950               S0      
317P12V             VIA        MD0040PA01X+009150Y+103050               S0      
317P12V             VIA        MD0040PA01X+009550Y+072800               S0      
317P12V             VIA        MD0040PA01X+009800Y+156470               S0      
317P12V             VIA        MD0040PA00X+010450Y+010100               S0      
317P12V             VIA        MD0040PA00X+001050Y+164880               S0      
317P12V             VIA        MD0040PA00X+010900Y+007650               S0      
317P12V             VIA        MD0040PA00X+010950Y+006200               S0      
317P12V             VIA        MD0040PA00X+011200Y+010100               S0      
317P12V             VIA        MD0040PA00X+011500Y+007650               S0      
317P12V             VIA        MD0040PA00X+011550Y+005950               S0      
317P12V             VIA        MD0040PA00X+014400Y+050950               S0      
317P12V             VIA        MD0040PA00X+015460Y+058150               S0      
317P12V             VIA        MD0040PA00X+015925Y+059025               S0      
317P12V             VIA        MD0040PA00X+016610Y+052790               S0      
317P12V             VIA        MD0040PA00X+002160Y+033380               S0      
317P12V             VIA        MD0040PA00X+003345Y+057430               S0      
317P12V             VIA        MD0040PA00X+004250Y+025410               S0      
317P12V             VIA        MD0040PA00X+004600Y+051600               S0      
317P12V             VIA        MD0040PA00X+004650Y+051100               S0      
317P12V             VIA        MD0040PA00X+004850Y+024860               S0      
317P12V             VIA        MD0040PA00X+005210Y+051310               S0      
317P12V             VIA        MD0040PA00X+005570Y+088000               S0      
317P12V             VIA        MD0040PA00X+006340Y+058140               S0      
317P12V             VIA        MD0040PA00X+006400Y+006755               S0      
317P12V             VIA        MD0040PA00X+006450Y+005300               S0      
317P12V             VIA        MD0040PA00X+006900Y+072680               S0      
317P12V             VIA        MD0040PA00X+007045Y+006003               S0      
317P12V             VIA        MD0040PA00X+007110Y+117100               S0      
317P12V             VIA        MD0040PA00X+008209Y+111250               S0      
317P12V             VIA        MD0040PA00X+008950Y+004950               S0      
317P12V             VIA        MD0040PA00X+009100Y+009700               S0      
317P12V             VIA        MD0040PA00X+009125Y+070470               S0      
317P12V             VIA        MD0040PA00X+009130Y+052820               S0      
317P12V             VIA        MD0040PA00X+009150Y+008850               S0      
317P12V             VIA        MD0040PA00X+009150Y+009250               S0      
317P12V             VIA        MD0040PA00X+009300Y+010700               S0      
317P12V             VIA        MD0040PA00X+009350Y+010150               S0      
317P12V             VIA        MD0040PA00X+009390Y+011180               S0      
317P12V             VIA        MD0040PA00X+009700Y+005150               S0      
317P12V             VIA        MD0040PA00X+009850Y+007300               S0      
317P12V             VIA        MD0040PA00X+009950Y+006100               S0      
317P12V             VIA        MD0040PA00X+010000Y+048800               S0      
317P12V             VIA        MD0040PA00X+010000Y+049400               S0      
317P12V             VIA        MD0040PA00X+010000Y+050000               S0      
317P12V             VIA        MD0040PA00X+010000Y+050600               S0      
317P12V             VIA        MD0040PA00X+010000Y+051200               S0      
317P12V             VIA        MD0040PA00X+010000Y+051910               S0      
317P12V             VIA        MD0040PA00X+010200Y+154400               S0      
317P12V             VIA        MD0040PA00X+010200Y+155000               S0      
317P12V             VIA        MD0040PA00X+010200Y+155600               S0      
317P12V             VIA        MD0040PA00X+010200Y+156200               S0      
317P12V             VIA        MD0040PA00X+010200Y+156800               S0      
317P12V             VIA        MD0040PA00X+010688Y+079420               S0      
317P12V             VIA        MD0040PA00X+010700Y+079820               S0      
317P12V             VIA        MD0040PA00X+010700Y+080240               S0      
317P12V             VIA        MD0040PA00X+011080Y+048260               S0      
317P12V             VIA        MD0040PA00X+011080Y+048860               S0      
317P12V             VIA        MD0040PA00X+011080Y+049460               S0      
317P12V             VIA        MD0040PA00X+011080Y+050060               S0      
317P12V             VIA        MD0040PA00X+011080Y+050660               S0      
317P12V             VIA        MD0040PA00X+011080Y+051260               S0      
317P12V             VIA        MD0040PA00X+011150Y+153750               S0      
317P12V             VIA        MD0040PA00X+011400Y+154600               S0      
317P12V             VIA        MD0040PA00X+011400Y+155200               S0      
317P12V             VIA        MD0040PA00X+011400Y+155800               S0      
317P12V             VIA        MD0040PA00X+011400Y+156400               S0      
317P12V             VIA        MD0040PA00X+011590Y+156970               S0      
317P12V             VIA        MD0040PA00X+011600Y+157600               S0      
317P12V             VIA        MD0040PA00X+011695Y+189200               S0      
317P12V             VIA        MD0040PA00X+011900Y+152950               S0      
317P12V             VIA        MD0040PA00X+012000Y+048550               S0      
317P12V             VIA        MD0040PA00X+012000Y+049350               S0      
317P12V             VIA        MD0040PA00X+012000Y+050150               S0      
317P12V             VIA        MD0040PA00X+012000Y+050950               S0      
317P12V             VIA        MD0040PA00X+012000Y+051750               S0      
317P12V             VIA        MD0040PA00X+012000Y+052350               S0      
317P12V             VIA        MD0040PA00X+012180Y+156993               S0      
317P12V             VIA        MD0040PA00X+012200Y+153800               S0      
317P12V             VIA        MD0040PA00X+012200Y+154600               S0      
317P12V             VIA        MD0040PA00X+012200Y+155200               S0      
317P12V             VIA        MD0040PA00X+012200Y+155800               S0      
317P12V             VIA        MD0040PA00X+012200Y+156400               S0      
317P12V             VIA        MD0040PA00X+012200Y+157600               S0      
317P12V             VIA        MD0040PA00X+012450Y+152400               S0      
317P12V             VIA        MD0040PA00X+012450Y+189240               S0      
317P12V             VIA        MD0040PA00X+012800Y+156800               S0      
317P12V             VIA        MD0040PA00X+012900Y+153500               S0      
317P12V             VIA        MD0040PA00X+012900Y+154250               S0      
317P12V             VIA        MD0040PA00X+012900Y+154900               S0      
317P12V             VIA        MD0040PA00X+012900Y+155550               S0      
317P12V             VIA        MD0040PA00X+012900Y+156250               S0      
317P12V             VIA        MD0040PA00X+012900Y+048550               S0      
317P12V             VIA        MD0040PA00X+012900Y+049350               S0      
317P12V             VIA        MD0040PA00X+012900Y+050150               S0      
317P12V             VIA        MD0040PA00X+012900Y+050950               S0      
317P12V             VIA        MD0040PA00X+012900Y+051750               S0      
317P12V             VIA        MD0040PA00X+012900Y+052350               S0      
317P12V             VIA        MD0040PA00X+013200Y+189200               S0      
317P12V             VIA        MD0040PA00X+013600Y+152800               S0      
317P12V             VIA        MD0040PA00X+013600Y+153600               S0      
317P12V             VIA        MD0040PA00X+013600Y+154200               S0      
317P12V             VIA        MD0040PA00X+013600Y+154800               S0      
317P12V             VIA        MD0040PA00X+013600Y+155500               S0      
317P12V             VIA        MD0040PA00X+013600Y+156200               S0      
317P12V             VIA        MD0040PA00X+013600Y+156800               S0      
317P12V             VIA        MD0040PA00X+013650Y+048550               S0      
317P12V             VIA        MD0040PA00X+013700Y+049300               S0      
317P12V             VIA        MD0040PA00X+013700Y+050150               S0      
317P12V             VIA        MD0040PA00X+013700Y+051000               S0      
317P12V             VIA        MD0040PA00X+013750Y+051750               S0      
317P12V             VIA        MD0040PA00X+013750Y+052350               S0      
317P12V             VIA        MD0040PA00X+001390Y+170620               S0      
317P12V             VIA        MD0040PA00X+014400Y+048618               S0      
317P12V             VIA        MD0040PA00X+014400Y+049350               S0      
317P12V             VIA        MD0040PA00X+014400Y+050150               S0      
317P12V             VIA        MD0040PA00X+014400Y+051750               S0      
317P12V             VIA        MD0040PA00X+014800Y+152800               S0      
317P12V             VIA        MD0040PA00X+014800Y+154200               S0      
317P12V             VIA        MD0040PA00X+014800Y+155000               S0      
317P12V             VIA        MD0040PA00X+014800Y+155800               S0      
317P12V             VIA        MD0040PA00X+014800Y+156400               S0      
317P12V             VIA        MD0040PA00X+014830Y+146500               S0      
317P12V             VIA        MD0040PA00X+015000Y+157000               S0      
317P12V             VIA        MD0040PA00X+015000Y+157600               S0      
317P12V             VIA        MD0040PA00X+015400Y+156400               S0      
317P12V             VIA        MD0040PA00X+015500Y+112000               S0      
317P12V             VIA        MD0040PA00X+015500Y+112500               S0      
317P12V             VIA        MD0040PA00X+015500Y+113050               S0      
317P12V             VIA        MD0040PA00X+015600Y+157000               S0      
317P12V             VIA        MD0040PA00X+015600Y+157600               S0      
317P12V             VIA        MD0040PA00X+015680Y+050690               S0      
317P12V             VIA        MD0040PA00X+015680Y+051540               S0      
317P12V             VIA        MD0040PA00X+015710Y+050000               S0      
317P12V             VIA        MD0040PA00X+016130Y+156310               S0      
317P12V             VIA        MD0040PA00X+016140Y+154350               S0      
317P12V             VIA        MD0040PA00X+016150Y+122750               S0      
317P12V             VIA        MD0040PA00X+016690Y+156710               S0      
317P12V             VIA        MD0040PA00X+016850Y+152600               S0      
317P12V             VIA        MD0040PA00X+016850Y+153350               S0      
317P12V             VIA        MD0040PA00X+016920Y+048280               S0      
317P12V             VIA        MD0040PA00X+016950Y+156150               S0      
317P12V             VIA        MD0040PA00X+017000Y+154100               S0      
317P12V             VIA        MD0040PA00X+017000Y+154850               S0      
317P12V             VIA        MD0040PA00X+017000Y+155500               S0      
317P12V             VIA        MD0040PA00X+017350Y+050600               S0      
317P12V             VIA        MD0040PA00X+017360Y+049880               S0      
317P12V             VIA        MD0040PA00X+017370Y+051390               S0      
317P12V             VIA        MD0040PA00X+017400Y+151550               S0      
317P12V             VIA        MD0040PA00X+017400Y+152200               S0      
317P12V             VIA        MD0040PA00X+017450Y+150350               S0      
317P12V             VIA        MD0040PA00X+017450Y+150950               S0      
317P12V             VIA        MD0040PA00X+017490Y+052330               S0      
317P12V             VIA        MD0040PA00X+018650Y+049800               S0      
317P12V             VIA        MD0040PA00X+018650Y+050600               S0      
317P12V             VIA        MD0040PA00X+018650Y+051350               S0      
317P12V             VIA        MD0040PA00X+018650Y+051900               S0      
317P12V             VIA        MD0040PA00X+019020Y+052340               S0      
317P12V             VIA        MD0040PA00X+019200Y+049000               S0      
317P12V             VIA        MD0040PA00X+019200Y+049800               S0      
317P12V             VIA        MD0040PA00X+019200Y+050600               S0      
317P12V             VIA        MD0040PA00X+019200Y+051350               S0      
317P12V             VIA        MD0040PA00X+019360Y+051910               S0      
317P12V             VIA        MD0040PA00X+019950Y+048940               S0      
317P12V             VIA        MD0040PA00X+019980Y+050600               S0      
317P12V             VIA        MD0040PA00X+020010Y+051360               S0      
317P12V             VIA        MD0040PA00X+020030Y+049810               S0      
317P12V             VIA        MD0040PA00X+020109Y+052350               S0      
317P12V             VIA        MD0040PA00X+020120Y+051920               S0      
317P12V             VIA        MD0040PA00X+003160Y+102430               S0      
317P12V             VIA        MD0040PA00X+003880Y+177500               S0      
317P12V             VIA        MD0040PA00X+003910Y+067492               S0      
317P12V             VIA        MD0040PA00X+004000Y+065900               S0      
317P12V             VIA        MD0040PA00X+004160Y+174690               S0      
317P12V             VIA        MD0040PA00X+004200Y+178440               S0      
317P12V             VIA        MD0040PA00X+004250Y+049300               S0      
317P12V             VIA        MD0040PA00X+004328Y+067499               S0      
317P12V             VIA        MD0040PA00X+004600Y+049050               S0      
317P12V             VIA        MD0040PA00X+004840Y+174690               S0      
317P12V             VIA        MD0040PA00X+005010Y+049300               S0      
317P12V             VIA        MD0040PA00X+005170Y+052250               S0      
317P12V             VIA        MD0040PA00X+005350Y+151900               S0      
317P12V             VIA        MD0040PA00X+005430Y+154120               S0      
317P12V             VIA        MD0040PA00X+005450Y+157400               S0      
317P12V             VIA        MD0040PA00X+005700Y+156850               S0      
317P12V             VIA        MD0040PA00X+005750Y+156200               S0      
317P12V             VIA        MD0040PA00X+005850Y+151900               S0      
317P12V             VIA        MD0040PA00X+005950Y+154100               S0      
317P12V             VIA        MD0040PA00X+006400Y+098050               S0      
317P12V             VIA        MD0040PA00X+007180Y+050690               S0      
317P12V             VIA        MD0040PA00X+007190Y+050100               S0      
317P12V             VIA        MD0040PA00X+007200Y+151400               S0      
317P12V             VIA        MD0040PA00X+007200Y+051480               S0      
317P12V             VIA        MD0040PA00X+007210Y+052180               S0      
317P12V             VIA        MD0040PA00X+007390Y+153590               S0      
317P12V             VIA        MD0040PA00X+007800Y+051480               S0      
317P12V             VIA        MD0040PA00X+007820Y+050100               S0      
317P12V             VIA        MD0040PA00X+007850Y+050670               S0      
317P12V             VIA        MD0040PA00X+007940Y+052180               S0      
317P12V             VIA        MD0040PA00X+008000Y+153160               S0      
317P12V             VIA        MD0040PA00X+008200Y+048360               S0      
317P12V             VIA        MD0040PA00X+008450Y+051440               S0      
317P12V             VIA        MD0040PA00X+008500Y+050640               S0      
317P12V             VIA        MD0040PA00X+008520Y+151500               S0      
317P12V             VIA        MD0040PA00X+008700Y+106300               S0      
317P12V             VIA        MD0040PA00X+008790Y+152340               S0      
317P12V             VIA        MD0040PA00X+009140Y+106410               S0      
317P12V             VIA        MD0040PA00X+009300Y+151870               S0      
317P12V             VIA        MD0040PA00X+009400Y+151400               S0      
317P12V             VIA        MD0040PA00X+009400Y+155000               S0      
317P12V             VIA        MD0040PA00X+009400Y+155600               S0      
317P12V             VIA        MD0040PA00X+009400Y+156200               S0      
317P12V             VIA        MD0040PA00X+009400Y+156800               S0      
317P12V             VIA        MD0040PA00X+009540Y+106410               S0      
317P12V             VIA        MD0040PA00X+009725Y+102350               S0      
317P12V             VIA        MD0040PA00X+009980Y+048200               S0      
317OTP_RETRY_G                  D0040PA01X+012113Y+140195               S0      
317OTP_RETRY_G                  D0040PA01X+013470Y+140400               S0      
317OTP_RETRY_G                  D0040PA01X+013500Y+140840               S0      
327OTP_RETRY_G                  D0040PA01X+011700Y+138750               S0      
327OTP_RETRY_G                  D0040PA01X+014300Y+138750               S0      
327OTP_RETRY_G                  D0040PA01X+013570Y+139230               S0      
317OTP_RETRY_G      VIA        MD0040PA01X+012286Y+138550               S0      
317FAN_TACH12                   D0040PA00X+001591Y+006811               S0      
317FAN_TACH12                   D0040PA01X+007140Y+007175               S0      
317FAN_TACH12                   D0040PA01X+006740Y+007100               S0      
317FAN_TACH12                   D0040PA01X+007570Y+007150               S0      
327FAN_TACH12                   D0040PA01X+009585Y+006850               S0      
317FAN_TACH10                   D0040PA00X+001591Y+050134               S0      
317FAN_TACH10                   D0040PA01X+003500Y+058130               S0      
317FAN_TACH10                   D0040PA01X+003900Y+058130               S0      
317FAN_TACH10                   D0040PA01X+004510Y+058290               S0      
327FAN_TACH10                   D0040PA01X+004505Y+059300               S0      
317FAN_TACH10       VIA        MD0040PA01X+002710Y+057810               S0      
317FAN_TACH10       VIA        MD0040PA00X+002515Y+057080               S0      
317FAN_TACH11                   D0040PA00X+001591Y+004811               S0      
317FAN_TACH11                   D0040PA01X+007180Y+005655               S0      
317FAN_TACH11                   D0040PA01X+006800Y+005650               S0      
317FAN_TACH11                   D0040PA01X+007825Y+006140               S0      
327FAN_TACH11                   D0040PA01X+007795Y+005450               S0      
327NCT7904_3VSB                 D0040PA01X+017010Y+060760               S0      
317NCT7904_3VSB                 D0040PA01X+016460Y+060850               S0      
317NCT7904_3VSB                 D0040PA01X+017642Y+061354               S0      
317NCT7904_3VSB                 D0040PA01X+009727Y+059407               S0      
327NCT7904_3VSB                 D0040PA01X+013624Y+062441               S0      
327NCT7904_3VSB                 D0040PA01X+010284Y+061850               S0      
317NCT7904_3VSB     VIA        MD0040PA01X+017630Y+060863               S0      
317FAN_TACH9                    D0040PA00X+001591Y+048134               S0      
317FAN_TACH9                    D0040PA01X+006450Y+057300               S0      
317FAN_TACH9                    D0040PA01X+006440Y+057720               S0      
317FAN_TACH9                    D0040PA01X+006790Y+059100               S0      
327FAN_TACH9                    D0040PA01X+007165Y+058400               S0      
317FAN_TACH9        VIA        MD0040PA04X+001804Y+057208               S0      
317FAN_TACH9        VIA        MD0040PA00X+002345Y+057749               S0      
317FAN_TACH6                    D0040PA00X+001591Y+120732               S0      
317FAN_TACH6                    D0040PA01X+005810Y+103080               S0      
317FAN_TACH6                    D0040PA01X+007230Y+102540               S0      
317FAN_TACH6                    D0040PA01X+006760Y+102500               S0      
327FAN_TACH6                    D0040PA01X+006445Y+103210               S0      
317FAN_TACH7                    D0040PA00X+001591Y+074118               S0      
317FAN_TACH7                    D0040PA01X+007570Y+071910               S0      
317FAN_TACH7                    D0040PA01X+008780Y+070790               S0      
317FAN_TACH7                    D0040PA01X+008200Y+070820               S0      
327FAN_TACH7                    D0040PA01X+008185Y+071540               S0      
317FAN_TACH8                    D0040PA00X+001591Y+076118               S0      
317FAN_TACH8                    D0040PA01X+007520Y+074150               S0      
317FAN_TACH8                    D0040PA01X+008630Y+073340               S0      
317FAN_TACH8                    D0040PA01X+008150Y+073320               S0      
327FAN_TACH8                    D0040PA01X+008135Y+074040               S0      
317FAN_TACH5                    D0040PA00X+001591Y+118732               S0      
317FAN_TACH5                    D0040PA01X+005380Y+101310               S0      
317FAN_TACH5                    D0040PA01X+006870Y+100430               S0      
317FAN_TACH5                    D0040PA01X+006420Y+100410               S0      
327FAN_TACH5                    D0040PA01X+006015Y+101180               S0      
317FAN_TACH3                    D0040PA00X+001591Y+144717               S0      
317FAN_TACH3                    D0040PA01X+007120Y+114450               S0      
317FAN_TACH3                    D0040PA01X+006350Y+112380               S0      
317FAN_TACH3                    D0040PA01X+006320Y+112835               S0      
327FAN_TACH3                    D0040PA01X+007020Y+113835               S0      
317FAN_TACH3        VIA        MD0040PA04X+003044Y+136756               S0      
317FAN_TACH3        VIA        MD0040PA00X+007050Y+116150               S0      
317FAN_TACH4                    D0040PA00X+001591Y+146717               S0      
317FAN_TACH4                    D0040PA01X+008700Y+114300               S0      
317FAN_TACH4                    D0040PA01X+008140Y+112610               S0      
317FAN_TACH4                    D0040PA01X+008140Y+113215               S0      
327FAN_TACH4                    D0040PA01X+008850Y+113625               S0      
317FAN_TACH4        VIA        MD0040PA00X+007316Y+115878               S0      
317FAN_TACH1                    D0040PA00X+001591Y+188039               S0      
317FAN_TACH1                    D0040PA01X+003030Y+178780               S0      
317FAN_TACH1                    D0040PA01X+003070Y+177440               S0      
317FAN_TACH1                    D0040PA01X+003360Y+176990               S0      
327FAN_TACH1                    D0040PA01X+002135Y+178100               S0      
317FAN_TACH1        VIA        MD0040PA01X+002006Y+177419               S0      
317FAN_TACH2                    D0040PA00X+001591Y+190039               S0      
317FAN_TACH2                    D0040PA01X+004820Y+176030               S0      
317FAN_TACH2                    D0040PA01X+004830Y+175570               S0      
317FAN_TACH2                    D0040PA01X+004870Y+176470               S0      
327FAN_TACH2                    D0040PA01X+004160Y+176755               S0      
317FAN_TACH2        VIA        MD0040PA01X+005700Y+180550               S0      
317NCT7904_VREF                 D0040PA01X+010350Y+059750               S0      
317NCT7904_VREF                 D0040PA01X+010500Y+060320               S0      
327NCT7904_VREF                 D0040PA01X+010871Y+061263               S0      
327NNAME00001                   D0040PA01X+015860Y+143800               S0      
317NNAME00001                   D0040PA01X+013330Y+143200               S0      
327NNAME00001                   D0040PA01X+013869Y+142227               S0      
317NNAME00001                   D0040PA01X+006060Y+019500               S0      
317NNAME00001                   D0040PA01X+006030Y+019930               S0      
317NNAME00001                   D0040PA01X+013320Y+142830               S0      
317NNAME00001                   D0040PA01X+014750Y+143725               S0      
317NNAME00001       VIA        MD0040PA04X+019201Y+048259               S0      
317NNAME00001       VIA        MD0040PA00X+014250Y+142050               S0      
317NNAME00001       VIA        MD0040PA00X+007050Y+019020               S0      
317NNAME00002                   D0040PA00X+008071Y+022441               S0      
317NNAME00002                   D0040PA00X+014961Y+022441               S0      
317NNAME00002                   D0040PA01X+006260Y+024920               S0      
317NNAME00002                   D0040PA01X+005620Y+025280               S0      
317NNAME00002                   D0040PA01X+005430Y+025990               S0      
317NNAME00003                   D0040PA00X+008071Y+024441               S0      
317NNAME00003                   D0040PA00X+014961Y+024441               S0      
317NNAME00003                   D0040PA01X+006300Y+026430               S0      
317NNAME00003                   D0040PA01X+006270Y+025980               S0      
317NNAME00003                   D0040PA01X+005830Y+025990               S0      
317ADM1276_ISET                 D0040PA01X+009480Y+144280               S0      
317ADM1276_ISET                 D0040PA01X+009470Y+143900               S0      
317ADM1276_ISET                 D0040PA01X+009470Y+144650               S0      
327ADM1276_ISET                 D0040PA01X+010740Y+145200               S0      
317ADM1276_ISET     VIA        MD0040PA01X+009970Y+145070               S0      
317NCT7904_D1+                  D0040PA01X+010760Y+059370               S0      
327NCT7904_D1+                  D0040PA01X+011202Y+056699               S0      
327NCT7904_D1+                  D0040PA01X+010452Y+057087               S0      
327NCT7904_D1+                  D0040PA01X+011067Y+061263               S0      
317NCT7904_D1+      VIA        MD0040PA01X+010634Y+058050               S0      
317NCT7904_D1-                  D0040PA01X+011120Y+059370               S0      
327NCT7904_D1-                  D0040PA01X+011202Y+057474               S0      
327NCT7904_D1-                  D0040PA01X+011265Y+061263               S0      
317NCT7904_D1-      VIA        MD0040PA01X+011202Y+058490               S0      
317NCT7904_D2+                  D0040PA01X+011290Y+060350               S0      
327NCT7904_D2+                  D0040PA01X+011202Y+125597               S0      
327NCT7904_D2+                  D0040PA01X+010452Y+125984               S0      
327NCT7904_D2+                  D0040PA01X+011462Y+061263               S0      
317NCT7904_D2+      VIA        MD0040PA04X+012400Y+124760               S0      
317NCT7904_D2+      VIA        MD0040PA00X+011366Y+059936               S0      
317NCT7904_D2+      VIA        MD0040PA00X+011900Y+125597               S0      
317NCT7904_D2-                  D0040PA01X+011650Y+060350               S0      
327NCT7904_D2-                  D0040PA01X+011202Y+126372               S0      
327NCT7904_D2-                  D0040PA01X+011658Y+061263               S0      
317NCT7904_D2-      VIA        MD0040PA04X+012269Y+125781               S0      
317NCT7904_D2-      VIA        MD0040PA00X+011600Y+059690               S0      
317NCT7904_D2-      VIA        MD0040PA00X+011950Y+126100               S0      
327P12V_FAN1                    D0040PA01X+008010Y+189985               S0      
317P12V_FAN1                    D0040PA00X+001591Y+191039               S0      
327P12V_FAN1                    D0040PA01X+009850Y+191000               S0      
317P12V_FAN1        VIA        MD0040PA01X+006600Y+191700               S0      
317P12V_FAN1        VIA        MD0040PA01X+008200Y+191500               S0      
317NNAME00004                   D0040PA00X+001591Y+189039               S0      
317NNAME00004                   D0040PA01X+003500Y+178820               S0      
317NNAME00004                   D0040PA01X+010260Y+088480               S0      
317NNAME00004       VIA        MD0040PA04X+005693Y+113003               S0      
317NNAME00004       VIA        MD0040PA00X+006460Y+088270               S0      
317NNAME00004       VIA        MD0040PA00X+003918Y+179231               S0      
317PWM_EXP_2B                   D0040PA00X+014961Y+020441               S0      
317PWM_EXP_2B                   D0040PA01X+009470Y+067100               S0      
327PWM_EXP_2B                   D0040PA01X+009321Y+067742               S0      
317PWM_EXP_2B       VIA        MD0040PA04X+010060Y+065660               S0      
317PWM_EXP_2B       VIA        MD0040PA00X+004992Y+015326               S0      
317PWM_EXP_2B       VIA        MD0040PA00X+007530Y+015530               S0      
317PWM_EXP_2B       VIA        MD0040PA00X+010060Y+067060               S0      
317PWM_EXP_2A                   D0040PA00X+015961Y+023441               S0      
317PWM_EXP_2A                   D0040PA01X+012596Y+069217               S0      
327PWM_EXP_2A                   D0040PA01X+011331Y+069242               S0      
317PWM_EXP_2A       VIA        MD0040PA00X+012070Y+069085               S0      
317SELF_2B_HB                   D0040PA00X+015961Y+021441               S0      
317SELF_2B_HB                   D0040PA01X+006030Y+016730               S0      
317NNAME00005                   D0040PA00X+016961Y+024441               S0      
317NNAME00005                   D0040PA01X+015800Y+057520               S0      
317NNAME00005       VIA        MD0040PA04X+018400Y+053650               S0      
317NNAME00005       VIA        MD0040PA00X+016000Y+056250               S0      
317NNAME00006                   D0040PA00X+016961Y+023441               S0      
327NNAME00006                   D0040PA01X+017210Y+054910               S0      
317NNAME00006                   D0040PA01X+015350Y+056660               S0      
317NNAME00006                   D0040PA01X+016570Y+055330               S0      
327NNAME00006                   D0040PA01X+015314Y+055925               S0      
317NNAME00006       VIA        MD0040PA00X+018259Y+054229               S0      
317SELF_2A_HB                   D0040PA00X+016961Y+022441               S0      
317SELF_2A_HB                   D0040PA01X+006030Y+018330               S0      
317SELF_2A_HB       VIA        MD0040PA00X+006440Y+018340               S0      
317SEB_PEER_2A_HB               D0040PA00X+016961Y+021441               S0      
317SEB_PEER_2A_HB               D0040PA01X+006030Y+017530               S0      
317SEB_PEER_2A_HB               D0040PA01X+006030Y+017130               S0      
327SEB_PEER_2A_HB               D0040PA01X+005175Y+069056               S0      
317SEB_PEER_2A_HB   VIA        MD0040PA00X+003243Y+017790               S0      
317SEB_PEER_2A_HB   VIA        MD0040PA00X+004450Y+069750               S0      
317SEB_PEER_2B_HB               D0040PA00X+016961Y+020441               S0      
317SEB_PEER_2B_HB               D0040PA01X+006030Y+015930               S0      
317SEB_PEER_2B_HB               D0040PA01X+005690Y+015530               S0      
327SEB_PEER_2B_HB               D0040PA01X+005175Y+068800               S0      
317SEB_PEER_2B_HB   VIA        MD0040PA00X+003930Y+017550               S0      
317SEB_PEER_2B_HB   VIA        MD0040PA00X+004339Y+069429               S0      
317NNAME00007                   D0040PA00X+017961Y+024441               S0      
317NNAME00007                   D0040PA01X+004990Y+021340               S0      
317NNAME00007       VIA        MD0040PA00X+012210Y+023010               S0      
317NNAME00007       VIA        MD0040PA00X+007530Y+021130               S0      
317LOWER_TRAY_ID                D0040PA00X+017961Y+023441               S0      
317LOWER_TRAY_ID                D0040PA01X+006120Y+021700               S0      
317LOWER_TRAY_ID                D0040PA01X+006120Y+022100               S0      
317LOWER_TRAY_ID    VIA        MD0040PA00X+011760Y+023490               S0      
317LOWER_TRAY_ID    VIA        MD0040PA00X+007060Y+021760               S0      
317NNAME00008                   D0040PA00X+011071Y+022441               S0      
317NNAME00008                   D0040PA00X+017961Y+022441               S0      
317NNAME00008                   D0040PA01X+006160Y+021130               S0      
317NNAME00008                   D0040PA01X+005740Y+021130               S0      
317NNAME00008       VIA        MD0040PA00X+007140Y+020815               S0      
317NNAME00009                   D0040PA00X+017961Y+021441               S0      
317NNAME00009                   D0040PA01X+006030Y+018730               S0      
317NNAME00009                   D0040PA01X+006060Y+019160               S0      
317NNAME00010                   D0040PA00X+017961Y+020441               S0      
317NNAME00010                   D0040PA01X+004990Y+021740               S0      
317NNAME00010       VIA        MD0040PA00X+007210Y+022170               S0      
317NNAME00010       VIA        MD0040PA00X+008568Y+023110               S0      
327P12V_FAN2                    D0040PA01X+010510Y+114345               S0      
317P12V_FAN2                    D0040PA00X+001591Y+147717               S0      
327P12V_FAN2                    D0040PA01X+012210Y+115210               S0      
317P12V_FAN2        VIA        MD0040PA01X+007100Y+123260               S0      
317NNAME00011                   D0040PA00X+001591Y+145717               S0      
317NNAME00011                   D0040PA01X+006880Y+117510               S0      
317NNAME00011                   D0040PA01X+011090Y+088480               S0      
317NNAME00011       VIA        MD0040PA04X+006090Y+089300               S0      
317NNAME00011       VIA        MD0040PA00X+006160Y+088520               S0      
317NNAME00011       VIA        MD0040PA00X+006880Y+117880               S0      
327P12V_FAN3                    D0040PA01X+006805Y+106970               S0      
317P12V_FAN3                    D0040PA00X+001591Y+121732               S0      
327P12V_FAN3                    D0040PA01X+006370Y+105010               S0      
317P12V_FAN3        VIA        MD0040PA01X+005210Y+113270               S0      
317NNAME00012                   D0040PA00X+001591Y+119732               S0      
317NNAME00012                   D0040PA01X+007240Y+102090               S0      
317NNAME00012                   D0040PA01X+011930Y+088480               S0      
317NNAME00012       VIA        MD0040PA04X+005850Y+091250               S0      
317NNAME00012       VIA        MD0040PA00X+005100Y+101800               S0      
317NNAME00012       VIA        MD0040PA00X+006720Y+088880               S0      
327P12V_FAN4                    D0040PA01X+008225Y+077670               S0      
317P12V_FAN4                    D0040PA00X+001591Y+077118               S0      
327P12V_FAN4                    D0040PA01X+007260Y+075790               S0      
317P12V_FAN4        VIA        MD0040PA01X+006500Y+076600               S0      
317P12V_FAN4        VIA        MD0040PA01X+006500Y+077500               S0      
317NNAME00013                   D0040PA00X+001591Y+075118               S0      
317NNAME00013                   D0040PA01X+006530Y+073000               S0      
317NNAME00013                   D0040PA01X+011960Y+082840               S0      
317NNAME00013       VIA        MD0040PA04X+010576Y+081426               S0      
317NNAME00013       VIA        MD0040PA00X+011490Y+082410               S0      
317NNAME00013       VIA        MD0040PA00X+008650Y+072350               S0      
327P12V_FAN5                    D0040PA01X+005600Y+061555               S0      
317P12V_FAN5                    D0040PA00X+001591Y+051134               S0      
327P12V_FAN5                    D0040PA01X+007340Y+060670               S0      
317P12V_FAN5        VIA        MD0040PA01X+001100Y+057800               S0      
317P12V_FAN5        VIA        MD0040PA01X+002730Y+059300               S0      
317P12V_FAN5        VIA        MD0040PA01X+003700Y+060500               S0      
317NNAME00014                   D0040PA00X+001591Y+049134               S0      
317NNAME00014                   D0040PA01X+003000Y+057080               S0      
317NNAME00014                   D0040PA01X+011120Y+082840               S0      
317NNAME00014       VIA        MD0040PA04X+003800Y+058950               S0      
317NNAME00014       VIA        MD0040PA00X+002700Y+057380               S0      
317NNAME00014       VIA        MD0040PA00X+005120Y+082700               S0      
327P12V_FAN6                    D0040PA01X+007765Y+010300               S0      
317P12V_FAN6                    D0040PA00X+001591Y+007811               S0      
327P12V_FAN6                    D0040PA01X+007220Y+008620               S0      
317NNAME00015                   D0040PA00X+001591Y+005811               S0      
317NNAME00015                   D0040PA01X+006730Y+006350               S0      
317NNAME00015                   D0040PA01X+010290Y+082840               S0      
317NNAME00015       VIA        MD0040PA04X+006960Y+066270               S0      
317NNAME00015       VIA        MD0040PA00X+006121Y+082835               S0      
317NNAME00015       VIA        MD0040PA00X+006350Y+006350               S0      
317PWM_EXP_1B                   D0040PA00X+008071Y+020441               S0      
317PWM_EXP_1B                   D0040PA01X+012586Y+068806               S0      
327PWM_EXP_1B                   D0040PA01X+011331Y+068742               S0      
317PWM_EXP_1B       VIA        MD0040PA00X+011958Y+068701               S0      
317PWM_EXP_1A                   D0040PA00X+009071Y+023441               S0      
317PWM_EXP_1A                   D0040PA01X+012586Y+068367               S0      
327PWM_EXP_1A                   D0040PA01X+011331Y+068242               S0      
317PWM_EXP_1A       VIA        MD0040PA00X+012150Y+068350               S0      
317SELF_1B_HB                   D0040PA00X+009071Y+021441               S0      
317SELF_1B_HB                   D0040PA01X+005690Y+015930               S0      
317SELF_1B_HB       VIA        MD0040PA00X+004970Y+020970               S0      
317SELF_1B_HB       VIA        MD0040PA00X+005270Y+016230               S0      
317NNAME00016                   D0040PA00X+010071Y+024441               S0      
317NNAME00016                   D0040PA01X+015280Y+058700               S0      
317NNAME00016       VIA        MD0040PA00X+014790Y+058810               S0      
317NNAME00017                   D0040PA00X+010071Y+023441               S0      
327NNAME00017                   D0040PA01X+010760Y+055830               S0      
317NNAME00017                   D0040PA01X+009130Y+056980               S0      
317NNAME00017                   D0040PA01X+009630Y+056330               S0      
327NNAME00017                   D0040PA01X+008934Y+056105               S0      
317NNAME00017       VIA        MD0040PA01X+009650Y+056760               S0      
317NNAME00017       VIA        MD0040PA00X+011530Y+055180               S0      
317NNAME00017       VIA        MD0040PA00X+012720Y+024600               S0      
317SELF_1A_HB                   D0040PA00X+010071Y+022441               S0      
317SELF_1A_HB                   D0040PA01X+005690Y+017530               S0      
317SELF_1A_HB       VIA        MD0040PA00X+004780Y+019920               S0      
317SELF_1A_HB       VIA        MD0040PA00X+005250Y+017520               S0      
317SELF_1A_HB       VIA        MD0040PA00X+005350Y+019970               S0      
317SEB_PEER_1A_HB               D0040PA00X+010071Y+021441               S0      
317SEB_PEER_1A_HB               D0040PA01X+005690Y+018330               S0      
317SEB_PEER_1A_HB               D0040PA01X+005690Y+017930               S0      
327SEB_PEER_1A_HB               D0040PA01X+003625Y+069056               S0      
317SEB_PEER_1A_HB   VIA        MD0040PA00X+004110Y+023100               S0      
317SEB_PEER_1A_HB   VIA        MD0040PA00X+004370Y+018120               S0      
317SEB_PEER_1A_HB   VIA        MD0040PA00X+004950Y+070350               S0      
317SEB_PEER_1B_HB               D0040PA00X+010071Y+020441               S0      
317SEB_PEER_1B_HB               D0040PA01X+005690Y+016730               S0      
317SEB_PEER_1B_HB               D0040PA01X+005690Y+016330               S0      
327SEB_PEER_1B_HB               D0040PA01X+003625Y+068800               S0      
317SEB_PEER_1B_HB   VIA        MD0040PA00X+003800Y+022850               S0      
317SEB_PEER_1B_HB   VIA        MD0040PA00X+004340Y+017432               S0      
317SEB_PEER_1B_HB   VIA        MD0040PA00X+004650Y+070550               S0      
317SEB_PEER_1B_HB   VIA        MD0040PA00X+006130Y+022940               S0      
317NNAME00018                   D0040PA00X+011071Y+024441               S0      
317NNAME00018                   D0040PA01X+004650Y+021740               S0      
317NNAME00018       VIA        MD0040PA00X+006940Y+022610               S0      
317NNAME00018       VIA        MD0040PA00X+007480Y+023180               S0      
317UPPER_TRAY_ID                D0040PA00X+011071Y+023441               S0      
317UPPER_TRAY_ID                D0040PA01X+006100Y+024000               S0      
317UPPER_TRAY_ID                D0040PA01X+005690Y+024000               S0      
317UPPER_TRAY_ID    VIA        MD0040PA00X+006990Y+023660               S0      
317UPPER_TRAY_ID    VIA        MD0040PA00X+007790Y+022903               S0      
317NNAME00019                   D0040PA00X+011071Y+021441               S0      
317NNAME00019                   D0040PA01X+005660Y+019500               S0      
317NNAME00019                   D0040PA01X+005690Y+019930               S0      
317NNAME00019       VIA        MD0040PA00X+006400Y+019970               S0      
317NNAME00020                   D0040PA00X+011071Y+020441               S0      
317NNAME00020                   D0040PA01X+004650Y+021340               S0      
327P3V3_AUX_BJT_B               D0040PA01X+013471Y+071050               S0      
327P3V3_AUX_BJT_B               D0040PA01X+013153Y+072255               S0      
317P3V3_AUX_BJT_B               D0040PA01X+012490Y+072260               S0      
317P3V3_AUX_BJT_B   VIA        MD0040PA01X+011750Y+072450               S0      
327NNAME00021                   D0040PA01X+015860Y+144640               S0      
327NNAME00021                   D0040PA01X+016937Y+144497               S0      
317NNAME00021                   D0040PA01X+015233Y+143108               S0      
317NNAME00021                   D0040PA01X+015663Y+143108               S0      
317NNAME00021       VIA        MD0040PA01X+016550Y+145060               S0      
327OTP_RETRY_C                  D0040PA01X+014110Y+140170               S0      
327OTP_RETRY_C                  D0040PA01X+015190Y+140895               S0      
317OTP_RETRY_C                  D0040PA01X+015550Y+141500               S0      
317OTP_RETRY_C      VIA        MD0040PA01X+015977Y+141437               S0      
327NNAME00022                   D0040PA01X+014110Y+141010               S0      
317NNAME00022                   D0040PA01X+013500Y+141180               S0      
317NNAME00022       VIA        MD0040PA01X+012900Y+141643               S0      
317TEMP_ALM#_JP_1               D0040PA00X+016500Y+137050               S0      
317TEMP_ALM#_JP_1               D0040PA01X+015550Y+142340               S0      
317TEMP_ALM#_JP_1               D0040PA01X+016083Y+142688               S0      
317TEMP_ALM#_JP_1               D0040PA01X+015663Y+142768               S0      
317TEMP_ALM#_JP_2               D0040PA00X+016500Y+138050               S0      
327TEMP_ALM#_JP_2               D0040PA01X+011380Y+140226               S0      
317OTP_RETRY_B                  D0040PA00X+016500Y+139050               S0      
327OTP_RETRY_B                  D0040PA01X+014803Y+140145               S0      
317OTP_RETRY_B                  D0040PA01X+015550Y+141920               S0      
317OTP_RETRY_B                  D0040PA01X+015140Y+139400               S0      
327NNAME00023                   D0040PA01X+002680Y+169920               S0      
327NNAME00023                   D0040PA01X+002342Y+170737               S0      
317NNAME00023                   D0040PA01X+002360Y+169280               S0      
317NNAME00023                   D0040PA00X+003130Y+173764               S0      
317NNAME00023       VIA        MD0040PA01X+003295Y+170945               S0      
317LED_DR_LED0_K                D0040PA01X+002590Y+172510               S0      
317LED_DR_LED0_K                D0040PA00X+003130Y+174764               S0      
317LED_DR_LED0                  D0040PA01X+014500Y+094920               S0      
317LED_DR_LED0                  D0040PA01X+001840Y+172070               S0      
327LED_DR_LED0                  D0040PA01X+014502Y+095950               S0      
317LED_DR_LED0                  D0040PA00X+003130Y+175764               S0      
317LED_DR_LED0      VIA        MD0040PA00X+014300Y+095303               S0      
317LED_DR_LED0      VIA        MD0040PA00X+001920Y+170700               S0      
327NNAME00024                   D0040PA01X+002720Y+165710               S0      
327NNAME00024                   D0040PA01X+003150Y+164155               S0      
317NNAME00024                   D0040PA01X+002200Y+164430               S0      
317NNAME00024                   D0040PA00X+003130Y+160994               S0      
317LED_DR_LED1_K                D0040PA01X+002200Y+164020               S0      
317LED_DR_LED1_K                D0040PA00X+003130Y+161994               S0      
317LED_DR_LED1                  D0040PA01X+003290Y+166420               S0      
317LED_DR_LED1                  D0040PA01X+014900Y+094920               S0      
327LED_DR_LED1                  D0040PA01X+014758Y+095950               S0      
317LED_DR_LED1                  D0040PA00X+003130Y+162994               S0      
317LED_DR_LED1      VIA        MD0040PA04X+012290Y+100740               S0      
317LED_DR_LED1      VIA        MD0040PA00X+014650Y+095303               S0      
317LED_DR_LED1      VIA        MD0040PA00X+001925Y+166310               S0      
327NNAME00025                   D0040PA01X+003900Y+103350               S0      
327NNAME00025                   D0040PA01X+002437Y+109308               S0      
317NNAME00025                   D0040PA01X+002430Y+110600               S0      
317NNAME00025                   D0040PA00X+003130Y+104459               S0      
317NNAME00025       VIA        MD0040PA01X+002450Y+110200               S0      
317LED_DR_LED2_K                D0040PA01X+003010Y+108360               S0      
317LED_DR_LED2_K                D0040PA00X+003130Y+105459               S0      
317LED_DR_LED2                  D0040PA01X+015300Y+094920               S0      
317LED_DR_LED2                  D0040PA01X+004140Y+109600               S0      
327LED_DR_LED2                  D0040PA01X+015014Y+095950               S0      
317LED_DR_LED2                  D0040PA00X+003130Y+106459               S0      
317LED_DR_LED2      VIA        MD0040PA04X+003750Y+099800               S0      
317LED_DR_LED2      VIA        MD0040PA00X+012720Y+101520               S0      
317LED_DR_LED2      VIA        MD0040PA00X+014977Y+095412               S0      
317LED_DR_LED2      VIA        MD0040PA00X+003750Y+109982               S0      
317LED_DR_LED2      VIA        MD0040PA00X+003770Y+099160               S0      
327NNAME00026                   D0040PA01X+004990Y+089480               S0      
327NNAME00026                   D0040PA01X+005482Y+090237               S0      
317NNAME00026                   D0040PA01X+004340Y+089610               S0      
317NNAME00026                   D0040PA00X+003130Y+090392               S0      
317NNAME00026       VIA        MD0040PA01X+006590Y+090000               S0      
317LED_DR_LED3_K                D0040PA01X+004540Y+091640               S0      
317LED_DR_LED3_K                D0040PA00X+003130Y+091392               S0      
317LED_DR_LED3                  D0040PA01X+015700Y+094920               S0      
317LED_DR_LED3                  D0040PA01X+006410Y+091280               S0      
327LED_DR_LED3                  D0040PA01X+015270Y+095950               S0      
317LED_DR_LED3                  D0040PA00X+003130Y+092392               S0      
317LED_DR_LED3      VIA        MD0040PA01X+007650Y+090050               S0      
317LED_DR_LED3      VIA        MD0040PA00X+014750Y+090050               S0      
317LED_DR_LED3      VIA        MD0040PA00X+015275Y+095247               S0      
327NNAME00027                   D0040PA01X+003630Y+032850               S0      
327NNAME00027                   D0040PA01X+002880Y+031285               S0      
317NNAME00027                   D0040PA01X+003250Y+032130               S0      
317NNAME00027                   D0040PA00X+003130Y+033856               S0      
317NNAME00027       VIA        MD0040PA01X+003620Y+031870               S0      
317LED_DR_LED4_K                D0040PA01X+003920Y+034720               S0      
317LED_DR_LED4_K                D0040PA00X+003130Y+034856               S0      
317LED_DR_LED4                  D0040PA01X+016350Y+099430               S0      
317LED_DR_LED4                  D0040PA01X+001928Y+031068               S0      
327LED_DR_LED4                  D0040PA01X+015526Y+098170               S0      
317LED_DR_LED4                  D0040PA00X+003130Y+035856               S0      
317LED_DR_LED4      VIA        MD0040PA04X+005781Y+085250               S0      
317LED_DR_LED4      VIA        MD0040PA00X+015500Y+097450               S0      
317LED_DR_LED4      VIA        MD0040PA00X+015780Y+089800               S0      
317LED_DR_LED4      VIA        MD0040PA00X+005600Y+088550               S0      
327NNAME00028                   D0040PA01X+002790Y+024690               S0      
327NNAME00028                   D0040PA01X+002360Y+025505               S0      
317NNAME00028                   D0040PA01X+003270Y+025350               S0      
317NNAME00028                   D0040PA00X+003130Y+021087               S0      
317LED_DR_LED5_K                D0040PA01X+003720Y+025350               S0      
317LED_DR_LED5_K                D0040PA00X+003130Y+022087               S0      
317LED_DR_LED5                  D0040PA01X+015950Y+099430               S0      
317LED_DR_LED5                  D0040PA01X+003608Y+026422               S0      
327LED_DR_LED5                  D0040PA01X+015270Y+098170               S0      
317LED_DR_LED5                  D0040PA00X+003130Y+023087               S0      
317LED_DR_LED5      VIA        MD0040PA04X+012860Y+066950               S0      
317LED_DR_LED5      VIA        MD0040PA00X+015050Y+097650               S0      
317LED_DR_LED5      VIA        MD0040PA00X+005400Y+027560               S0      
327OSC_TRI_S                    D0040PA01X+017137Y+064584               S0      
317OSC_TRI_S                    D0040PA01X+018037Y+064577               S0      
317OSC_TRI_S        VIA        MD0040PA01X+017410Y+065290               S0      
327NCT7904_CLK                  D0040PA01X+015980Y+063482               S0      
317NCT7904_CLK                  D0040PA01X+015134Y+063583               S0      
317NCT7904_CLK      VIA        MD0040PA01X+015134Y+064040               S0      
327ADM1276_VCC                  D0040PA01X+010677Y+148064               S0      
317ADM1276_VCC                  D0040PA01X+010680Y+147450               S0      
317ADM1276_VCC                  D0040PA01X+010750Y+148680               S0      
327ADM1276_VCC                  D0040PA01X+011444Y+146160               S0      
317ADM1276_VCC      VIA        MD0040PA01X+011183Y+146967               S0      
317ADM1276_UV                   D0040PA01X+008770Y+148400               S0      
317ADM1276_UV                   D0040PA01X+009130Y+145100               S0      
317ADM1276_UV                   D0040PA01X+009350Y+147580               S0      
317ADM1276_UV                   D0040PA01X+010050Y+142030               S0      
327ADM1276_UV                   D0040PA01X+008780Y+147750               S0      
327ADM1276_UV                   D0040PA01X+011188Y+146160               S0      
317ADM1276_UV       VIA        MD0040PA04X+008960Y+146400               S0      
317ADM1276_UV       VIA        MD0040PA00X+008690Y+145100               S0      
317ADM1276_UV       VIA        MD0040PA00X+009130Y+148860               S0      
317ADM1276_UV       VIA        MD0040PA00X+009960Y+141650               S0      
317ADM1276_SS                   D0040PA01X+009480Y+143490               S0      
327ADM1276_SS                   D0040PA01X+010740Y+144944               S0      
317ADM1276_SS       VIA        MD0040PA01X+010000Y+144300               S0      
317ADM1276_VCAP                 D0040PA01X+009130Y+143900               S0      
317ADM1276_VCAP                 D0040PA01X+009470Y+145100               S0      
317ADM1276_VCAP                 D0040PA01X+009150Y+142370               S0      
317ADM1276_VCAP                 D0040PA01X+009480Y+145550               S0      
327ADM1276_VCAP                 D0040PA01X+010740Y+145456               S0      
317ADM1276_VCAP     VIA        MD0040PA04X+009586Y+144836               S0      
317ADM1276_VCAP     VIA        MD0040PA00X+008900Y+142817               S0      
317ADM1276_VCAP     VIA        MD0040PA00X+008720Y+144000               S0      
317ADM1276_VCAP     VIA        MD0040PA00X+009980Y+145560               S0      
317P3V3_IN                      D0040PA01X+005710Y+097490               S0      
327P3V3_IN                      D0040PA01X+006380Y+097560               S0      
317P3V3_IN                      D0040PA01X+007080Y+097580               S0      
327P3V3_IN                      D0040PA01X+007740Y+097630               S0      
317P3V3_IN          VIA        MD0040PA01X+005150Y+097410               S0      
317P3V3_BS_NET                  D0040PA01X+008190Y+096620               S0      
327P3V3_BS_NET                  D0040PA01X+008800Y+097255               S0      
317P3V3_BS_NET      VIA        MD0040PA01X+008760Y+096590               S0      
327P3V3_LX                      D0040PA01X+006390Y+094960               S0      
317P3V3_LX                      D0040PA01X+007830Y+096620               S0      
327P3V3_LX                      D0040PA01X+007740Y+097255               S0      
317P3V3_LX          VIA        MD0040PA01X+006000Y+096680               S0      
317P3V3_LX          VIA        MD0040PA01X+006690Y+096910               S0      
317P3V3_LX          VIA        MD0040PA01X+007300Y+096600               S0      
327P3V3_LX_COPPER               D0040PA01X+010450Y+093948               S0      
327P3V3_LX_COPPER               D0040PA01X+008670Y+094960               S0      
317P3V3_LX_COPPER               D0040PA01X+010350Y+097420               S0      
327P3V3_LX_COPPER               D0040PA01X+009600Y+094200               S0      
317P3V3_LX_COPPER               D0040PA01X+009400Y+095720               S0      
317P3V3_LX_COPPER   VIA        MD0040PA01X+010350Y+096650               S0      
317P3V3_LX_COPPER   VIA        MD0040PA01X+009450Y+095050               S0      
317P3V3_FB                      D0040PA01X+009900Y+097970               S0      
317P3V3_FB                      D0040PA01X+010350Y+097980               S0      
317P3V3_FB                      D0040PA01X+009450Y+098230               S0      
327P3V3_FB                      D0040PA01X+008800Y+098005               S0      
317P3V3_FB          VIA        MD0040PA01X+009054Y+098796               S0      
317ADM1276_TIMER                D0040PA01X+009480Y+143150               S0      
327ADM1276_TIMER                D0040PA01X+010740Y+144688               S0      
317ADM1276_TIMER    VIA        MD0040PA01X+010020Y+143380               S0      
317NNAME00029                   D0040PA01X+013220Y+148200               S0      
317NNAME00029                   D0040PA01X+013350Y+147680               S0      
317NNAME00029       VIA        MD0040PA01X+013650Y+148143               S0      
327NNAME00030                   D0040PA01X+015775Y+161330               S0      
327NNAME00030                   D0040PA01X+013025Y+161330               S0      
327NNAME00030                   D0040PA01X+010175Y+161330               S0      
327NNAME00030                   D0040PA01X+007125Y+161330               S0      
327NNAME00030                   D0040PA01X+018370Y+160650               S0      
327NNAME00030                   D0040PA01X+006790Y+159017               S0      
327NNAME00030                   D0040PA01X+010100Y+159007               S0      
327NNAME00030                   D0040PA01X+013600Y+159007               S0      
327NNAME00030                   D0040PA01X+017000Y+159007               S0      
317NNAME00030       VIA        MD0040PA01X+012050Y+160600               S0      
317NNAME00030       VIA        MD0040PA01X+005330Y+160920               S0      
317NNAME00030       VIA        MD0040PA01X+006440Y+160590               S0      
317NNAME00030       VIA        MD0040PA01X+008950Y+161000               S0      
317NNAME00030       VIA        MD0040PA00X+010400Y+160550               S0      
317NNAME00030       VIA        MD0040PA00X+011350Y+160550               S0      
317NNAME00030       VIA        MD0040PA00X+011600Y+158400               S0      
317NNAME00030       VIA        MD0040PA00X+011600Y+159200               S0      
317NNAME00030       VIA        MD0040PA00X+011600Y+160000               S0      
317NNAME00030       VIA        MD0040PA00X+011600Y+161200               S0      
317NNAME00030       VIA        MD0040PA00X+012200Y+158400               S0      
317NNAME00030       VIA        MD0040PA00X+012200Y+159200               S0      
317NNAME00030       VIA        MD0040PA00X+012200Y+160000               S0      
317NNAME00030       VIA        MD0040PA00X+012200Y+161200               S0      
317NNAME00030       VIA        MD0040PA00X+012800Y+160600               S0      
317NNAME00030       VIA        MD0040PA00X+013850Y+160600               S0      
317NNAME00030       VIA        MD0040PA00X+014600Y+161200               S0      
317NNAME00030       VIA        MD0040PA00X+014800Y+160600               S0      
317NNAME00030       VIA        MD0040PA00X+015050Y+158200               S0      
317NNAME00030       VIA        MD0040PA00X+015050Y+159100               S0      
317NNAME00030       VIA        MD0040PA00X+015050Y+160000               S0      
317NNAME00030       VIA        MD0040PA00X+015600Y+158200               S0      
317NNAME00030       VIA        MD0040PA00X+015600Y+160600               S0      
317NNAME00030       VIA        MD0040PA00X+015650Y+159100               S0      
317NNAME00030       VIA        MD0040PA00X+015650Y+160000               S0      
317NNAME00030       VIA        MD0040PA00X+016400Y+160600               S0      
317NNAME00030       VIA        MD0040PA00X+017200Y+160600               S0      
317NNAME00030       VIA        MD0040PA00X+018250Y+158450               S0      
317NNAME00030       VIA        MD0040PA00X+018250Y+159200               S0      
317NNAME00030       VIA        MD0040PA00X+018250Y+159940               S0      
317NNAME00030       VIA        MD0040PA00X+005060Y+158280               S0      
317NNAME00030       VIA        MD0040PA00X+005060Y+158930               S0      
317NNAME00030       VIA        MD0040PA00X+005060Y+159530               S0      
317NNAME00030       VIA        MD0040PA00X+005060Y+160130               S0      
317NNAME00030       VIA        MD0040PA00X+005530Y+158260               S0      
317NNAME00030       VIA        MD0040PA00X+005530Y+158910               S0      
317NNAME00030       VIA        MD0040PA00X+005530Y+159510               S0      
317NNAME00030       VIA        MD0040PA00X+005530Y+160110               S0      
317NNAME00030       VIA        MD0040PA00X+005540Y+161330               S0      
317NNAME00030       VIA        MD0040PA00X+005850Y+160770               S0      
317NNAME00030       VIA        MD0040PA00X+006870Y+160390               S0      
317NNAME00030       VIA        MD0040PA00X+007160Y+160770               S0      
317NNAME00030       VIA        MD0040PA00X+009450Y+160550               S0      
317P12VU_2490_RC                D0040PA01X+009860Y+055330               S0      
317P12VU_2490_RC                D0040PA01X+009870Y+054960               S0      
317P12VU_2490_RC    VIA        MD0040PA01X+010180Y+055740               S0      
317P12VL_2490_RC                D0040PA01X+016340Y+054930               S0      
317P12VL_2490_RC                D0040PA01X+016330Y+054560               S0      
317P12VL_2490_RC    VIA        MD0040PA01X+016420Y+054190               S0      
317NNAME00031                   D0040PA01X+008680Y+053780               S0      
317NNAME00031                   D0040PA01X+008140Y+053390               S0      
317NNAME00031                   D0040PA01X+008593Y+053368               S0      
327NNAME00031                   D0040PA01X+008737Y+054475               S0      
317NNAME00031       VIA        MD0040PA01X+007740Y+053630               S0      
317P12VU_2490_VCC               D0040PA01X+009610Y+053780               S0      
317P12VU_2490_VCC               D0040PA01X+009040Y+053780               S0      
317P12VU_2490_VCC               D0040PA01X+009610Y+053390               S0      
317P12VU_2490_VCC               D0040PA01X+009153Y+053368               S0      
327P12VU_2490_VCC               D0040PA01X+008934Y+054475               S0      
317P12VU_2490_VCC   VIA        MD0040PA01X+009690Y+054160               S0      
317NNAME00032                   D0040PA01X+016090Y+053650               S0      
317NNAME00032                   D0040PA01X+015560Y+053240               S0      
317NNAME00032                   D0040PA01X+016030Y+053210               S0      
327NNAME00032                   D0040PA01X+015117Y+054295               S0      
317NNAME00032       VIA        MD0040PA01X+015150Y+053300               S0      
317P12VL_2490_VCC               D0040PA01X+016450Y+053650               S0      
317P12VL_2490_VCC               D0040PA01X+017060Y+053640               S0      
317P12VL_2490_VCC               D0040PA01X+017060Y+053250               S0      
317P12VL_2490_VCC               D0040PA01X+016590Y+053210               S0      
327P12VL_2490_VCC               D0040PA01X+015314Y+054295               S0      
317P12VL_2490_VCC   VIA        MD0040PA01X+017480Y+053220               S0      
317ADM1276_OV                   D0040PA01X+008350Y+146180               S0      
317ADM1276_OV                   D0040PA01X+009550Y+146080               S0      
327ADM1276_OV                   D0040PA01X+008950Y+146170               S0      
327ADM1276_OV                   D0040PA01X+010740Y+145712               S0      
317ADM1276_OV       VIA        MD0040PA01X+010100Y+146075               S0      
317NNAME00033                   D0040PA01X+007410Y+057060               S0      
327NNAME00033                   D0040PA01X+008343Y+056105               S0      
317NNAME00033       VIA        MD0040PA01X+007040Y+056550               S0      
317NNAME00034                   D0040PA01X+014040Y+056680               S0      
327NNAME00034                   D0040PA01X+014723Y+055925               S0      
317NNAME00034       VIA        MD0040PA01X+013520Y+056640               S0      
317NNAME00035                   D0040PA01X+008740Y+057410               S0      
317NNAME00035                   D0040PA01X+008710Y+056990               S0      
327NNAME00035                   D0040PA01X+008737Y+056105               S0      
317NNAME00035       VIA        MD0040PA01X+008362Y+058174               S0      
317NNAME00036                   D0040PA01X+014950Y+057860               S0      
317NNAME00036                   D0040PA01X+014870Y+056800               S0      
327NNAME00036                   D0040PA01X+015117Y+055925               S0      
317NNAME00036       VIA        MD0040PA01X+014950Y+057460               S0      
317NNAME00037                   D0040PA01X+014850Y+147410               S0      
327NNAME00037                   D0040PA01X+014230Y+147180               S0      
317NNAME00037       VIA        MD0040PA01X+014850Y+147950               S0      
317ADM1276_GATE                 D0040PA01X+012900Y+147685               S0      
317ADM1276_GATE                 D0040PA01X+012880Y+148200               S0      
327ADM1276_GATE                 D0040PA01X+014230Y+148080               S0      
317ADM1276_GATE                 D0040PA01X+013790Y+148770               S0      
317ADM1276_GATE                 D0040PA01X+014200Y+148780               S0      
317ADM1276_GATE                 D0040PA01X+014650Y+148780               S0      
317ADM1276_GATE                 D0040PA01X+015100Y+148780               S0      
317ADM1276_GATE     VIA        MD0040PA01X+013018Y+148668               S0      
327NNAME00038                   D0040PA01X+010850Y+157550               S0      
317NNAME00038                   D0040PA01X+014200Y+149120               S0      
317NNAME00038       VIA        MD0040PA04X+010850Y+155650               S0      
317NNAME00038       VIA        MD0040PA04X+013400Y+151950               S0      
317NNAME00038       VIA        MD0040PA00X+010850Y+156900               S0      
317NNAME00038       VIA        MD0040PA00X+014200Y+149480               S0      
327NNAME00039                   D0040PA01X+008400Y+044000               S0      
317NNAME00039                   D0040PA01X+007080Y+043130               S0      
317NNAME00039       VIA        MD0040PA01X+007090Y+042720               S0      
327P12VU_NET                    D0040PA01X+009000Y+047355               S0      
327P12VU_NET                    D0040PA01X+007200Y+047355               S0      
317P12VU_NET                    D0040PA01X+008140Y+053050               S0      
327P12VU_NET                    D0040PA01X+007650Y+045456               S0      
327P12VU_NET                    D0040PA01X+010400Y+045407               S0      
317P12VU_NET        VIA        MD0040PA01X+010650Y+046950               S0      
317P12VU_NET        VIA        MD0040PA01X+011550Y+047670               S0      
317P12VU_NET        VIA        MD0040PA00X+008770Y+052800               S0      
317P12VU_NET        VIA        MD0040PA00X+011150Y+047300               S0      
317P12VU_NET        VIA        MD0040PA00X+011700Y+044900               S0      
317P12VU_NET        VIA        MD0040PA00X+011700Y+045500               S0      
317P12VU_NET        VIA        MD0040PA00X+011700Y+046050               S0      
317P12VU_NET        VIA        MD0040PA00X+011700Y+046600               S0      
317P12VU_NET        VIA        MD0040PA00X+011700Y+047150               S0      
317P12VU_NET        VIA        MD0040PA00X+012150Y+047550               S0      
317P12VU_NET        VIA        MD0040PA00X+012250Y+045050               S0      
317P12VU_NET        VIA        MD0040PA00X+012250Y+045750               S0      
317P12VU_NET        VIA        MD0040PA00X+012250Y+046350               S0      
317P12VU_NET        VIA        MD0040PA00X+012250Y+046950               S0      
317P12VU_NET        VIA        MD0040PA00X+006250Y+047290               S0      
317P12VU_NET        VIA        MD0040PA00X+006250Y+047700               S0      
317P12VU_NET        VIA        MD0040PA00X+006260Y+046850               S0      
317P12VU_NET        VIA        MD0040PA00X+006330Y+046440               S0      
317P12VU_NET        VIA        MD0040PA00X+006400Y+044650               S0      
317P12VU_NET        VIA        MD0040PA00X+006400Y+045100               S0      
317P12VU_NET        VIA        MD0040PA00X+006400Y+045550               S0      
317P12VU_NET        VIA        MD0040PA00X+006400Y+046000               S0      
317P12VU_NET        VIA        MD0040PA00X+007820Y+048170               S0      
317P12VU_NET        VIA        MD0040PA00X+008980Y+044600               S0      
317P12VU_NET        VIA        MD0040PA00X+008980Y+045290               S0      
317P12VU_NET        VIA        MD0040PA00X+008980Y+045900               S0      
317P12VU_NET        VIA        MD0040PA00X+008980Y+046480               S0      
317P12VU_NET        VIA        MD0040PA00X+009950Y+047300               S0      
327NNAME00040                   D0040PA01X+018400Y+043950               S0      
317NNAME00040                   D0040PA01X+019080Y+043950               S0      
317NNAME00040       VIA        MD0040PA01X+018993Y+043580               S0      
327P12VL_NET                    D0040PA01X+015800Y+047305               S0      
327P12VL_NET                    D0040PA01X+017600Y+047305               S0      
317P12VL_NET                    D0040PA01X+015560Y+052900               S0      
327P12VL_NET                    D0040PA01X+017650Y+045407               S0      
327P12VL_NET                    D0040PA01X+014850Y+045407               S0      
317P12VL_NET        VIA        MD0040PA01X+014440Y+047080               S0      
317P12VL_NET        VIA        MD0040PA00X+016250Y+052790               S0      
317P12VL_NET        VIA        MD0040PA00X+016530Y+048110               S0      
317P12VL_NET        VIA        MD0040PA00X+013050Y+045400               S0      
317P12VL_NET        VIA        MD0040PA00X+013050Y+046100               S0      
317P12VL_NET        VIA        MD0040PA00X+013050Y+046800               S0      
317P12VL_NET        VIA        MD0040PA00X+013050Y+047450               S0      
317P12VL_NET        VIA        MD0040PA00X+013100Y+044700               S0      
317P12VL_NET        VIA        MD0040PA00X+013550Y+045400               S0      
317P12VL_NET        VIA        MD0040PA00X+013550Y+046100               S0      
317P12VL_NET        VIA        MD0040PA00X+013550Y+046800               S0      
317P12VL_NET        VIA        MD0040PA00X+013550Y+047450               S0      
317P12VL_NET        VIA        MD0040PA00X+013600Y+044700               S0      
317P12VL_NET        VIA        MD0040PA00X+016160Y+044590               S0      
317P12VL_NET        VIA        MD0040PA00X+016190Y+045160               S0      
317P12VL_NET        VIA        MD0040PA00X+016190Y+046330               S0      
317P12VL_NET        VIA        MD0040PA00X+016200Y+045760               S0      
317P12VL_NET        VIA        MD0040PA00X+018850Y+047450               S0      
317P12VL_NET        VIA        MD0040PA00X+018990Y+046050               S0      
317P12VL_NET        VIA        MD0040PA00X+018990Y+046750               S0      
317P12VL_NET        VIA        MD0040PA00X+019024Y+044745               S0      
317P12VL_NET        VIA        MD0040PA00X+019040Y+045350               S0      
317P12VL_NET        VIA        MD0040PA00X+019450Y+047450               S0      
317P12VL_NET        VIA        MD0040PA00X+019500Y+046050               S0      
317P12VL_NET        VIA        MD0040PA00X+019500Y+046750               S0      
317P12VL_NET        VIA        MD0040PA00X+019550Y+045350               S0      
317P12VL_NET        VIA        MD0040PA00X+019560Y+044750               S0      
327NNAME00041                   D0040PA01X+007540Y+157560               S0      
317NNAME00041                   D0040PA01X+013790Y+149110               S0      
317NNAME00041       VIA        MD0040PA04X+008190Y+151020               S0      
317NNAME00041       VIA        MD0040PA00X+013230Y+149110               S0      
317NNAME00041       VIA        MD0040PA00X+006770Y+156870               S0      
327NNAME00042                   D0040PA01X+014350Y+157550               S0      
317NNAME00042                   D0040PA01X+014650Y+149120               S0      
317NNAME00042       VIA        MD0040PA04X+014352Y+154000               S0      
317NNAME00042       VIA        MD0040PA04X+014750Y+150500               S0      
317NNAME00042       VIA        MD0040PA00X+014352Y+156752               S0      
317NNAME00042       VIA        MD0040PA00X+014750Y+149800               S0      
327NNAME00043                   D0040PA01X+017750Y+157550               S0      
317NNAME00043                   D0040PA01X+015100Y+149120               S0      
317NNAME00043       VIA        MD0040PA04X+015700Y+152800               S0      
317NNAME00043       VIA        MD0040PA00X+015350Y+149650               S0      
317NNAME00043       VIA        MD0040PA00X+017750Y+156950               S0      
317ADM1276_EN_NET               D0040PA01X+016070Y+145800               S0      
317ADM1276_EN_NET               D0040PA01X+013750Y+144370               S0      
327ADM1276_EN_NET               D0040PA01X+016700Y+145770               S0      
317ADM1276_EN_NET               D0040PA01X+014363Y+144475               S0      
317ADM1276_EN_NET   VIA        MD0040PA01X+013800Y+144850               S0      
327ADM1276_LATCH#               D0040PA01X+016549Y+143747               S0      
317ADM1276_LATCH#               D0040PA01X+016540Y+143020               S0      
317ADM1276_LATCH#               D0040PA01X+010500Y+142370               S0      
317ADM1276_LATCH#               D0040PA01X+010970Y+142590               S0      
317ADM1276_LATCH#               D0040PA01X+010050Y+142370               S0      
317ADM1276_LATCH#               D0040PA01X+016083Y+143028               S0      
327ADM1276_LATCH#               D0040PA01X+011188Y+144240               S0      
317ADM1276_LATCH#   VIA        MD0040PA01X+010300Y+142950               S0      
317ADM1276_LATCH#   VIA        MD0040PA00X+011000Y+142950               S0      
317ADM1276_LATCH#   VIA        MD0040PA00X+013200Y+143650               S0      
327NNAME00044                   D0040PA01X+011150Y+043950               S0      
317NNAME00044                   D0040PA01X+011790Y+043750               S0      
317NNAME00044       VIA        MD0040PA01X+011850Y+044200               S0      
327NNAME00045                   D0040PA01X+015600Y+043950               S0      
317NNAME00045                   D0040PA01X+015350Y+043080               S0      
317NNAME00045       VIA        MD0040PA01X+016261Y+043817               S0      
327TEMP_ALM#_IN                 D0040PA01X+014163Y+068225               S0      
317TEMP_ALM#_IN                 D0040PA01X+015450Y+068380               S0      
317TEMP_ALM#_IN     VIA        MD0040PA01X+014550Y+067500               S0      
317NNAME00046                   D0040PA01X+012900Y+147415               S0      
327NNAME00046                   D0040PA01X+012212Y+146160               S0      
317NNAME00046       VIA        MD0040PA01X+012730Y+146880               S0      
317NNAME00047                   D0040PA01X+019420Y+043950               S0      
317NNAME00047                   D0040PA01X+015990Y+054560               S0      
317NNAME00047                   D0040PA01X+015010Y+043080               S0      
327NNAME00047                   D0040PA01X+014920Y+054295               S0      
317NNAME00047       VIA        MD0040PA04X+017930Y+053000               S0      
317NNAME00047       VIA        MD0040PA00X+014696Y+043240               S0      
317NNAME00047       VIA        MD0040PA00X+015985Y+054180               S0      
317NNAME00047       VIA        MD0040PA00X+019140Y+043241               S0      
317NNAME00048                   D0040PA01X+007420Y+043130               S0      
317NNAME00048                   D0040PA01X+012130Y+043750               S0      
317NNAME00048                   D0040PA01X+010210Y+054960               S0      
327NNAME00048                   D0040PA01X+008540Y+054475               S0      
317NNAME00048       VIA        MD0040PA04X+010530Y+052520               S0      
317NNAME00048       VIA        MD0040PA01X+009980Y+054560               S0      
317NNAME00048       VIA        MD0040PA00X+011040Y+055080               S0      
317NNAME00048       VIA        MD0040PA00X+012250Y+044100               S0      
317NNAME00048       VIA        MD0040PA00X+007800Y+042950               S0      
317P12VU_2490_PG                D0040PA01X+007370Y+054330               S0      
317P12VU_2490_PG                D0040PA01X+007390Y+055540               S0      
317P12VU_2490_PG                D0040PA01X+007390Y+055010               S0      
327P12VU_2490_PG                D0040PA01X+008146Y+054475               S0      
317P12VL_2490_PG                D0040PA01X+013678Y+054307               S0      
317P12VL_2490_PG                D0040PA01X+013668Y+055377               S0      
317P12VL_2490_PG                D0040PA01X+013677Y+054852               S0      
327P12VL_2490_PG                D0040PA01X+014527Y+054295               S0      
317ADM1276_ADR                  D0040PA01X+009560Y+142030               S0      
317ADM1276_ADR                  D0040PA01X+009150Y+142030               S0      
327ADM1276_ADR                  D0040PA01X+011444Y+144240               S0      
317ADM1276_ADR      VIA        MD0040PA04X+010160Y+143100               S0      
317ADM1276_ADR      VIA        MD0040PA00X+010950Y+143800               S0      
317ADM1276_ADR      VIA        MD0040PA00X+009850Y+142840               S0      
317NNAME00049                   D0040PA01X+008370Y+056990               S0      
317NNAME00049                   D0040PA01X+007860Y+057110               S0      
327NNAME00049                   D0040PA01X+008540Y+056105               S0      
317NNAME00049       VIA        MD0040PA01X+008290Y+057450               S0      
317NNAME00050                   D0040PA01X+014530Y+056800               S0      
317NNAME00050                   D0040PA01X+014530Y+057880               S0      
327NNAME00050                   D0040PA01X+014920Y+055925               S0      
317NNAME00050       VIA        MD0040PA01X+014523Y+057170               S0      
317ADM1276_EN                   D0040PA01X+012500Y+140945               S0      
317ADM1276_EN                   D0040PA01X+017520Y+070110               S0      
317ADM1276_EN                   D0040PA01X+011310Y+142590               S0      
317ADM1276_EN                   D0040PA01X+011310Y+142160               S0      
317ADM1276_EN                   D0040PA01X+013750Y+144030               S0      
327ADM1276_EN                   D0040PA01X+011700Y+144240               S0      
317ADM1276_EN       VIA        MD0040PA04X+012250Y+143751               S0      
317ADM1276_EN       VIA        MD0040PA00X+013117Y+141270               S0      
317ADM1276_EN       VIA        MD0040PA00X+015520Y+067950               S0      
317ADM1276_EN       VIA        MD0040PA00X+011700Y+143520               S0      
317ADM1276_EN       VIA        MD0040PA00X+013380Y+144070               S0      
317ADM1276_GPIO2                D0040PA01X+011800Y+142420               S0      
317ADM1276_GPIO2                D0040PA01X+011710Y+143010               S0      
327ADM1276_GPIO2                D0040PA01X+011956Y+144240               S0      
317ADM1276_SENSE+               D0040PA01X+010900Y+149830               S0      
317ADM1276_SENSE+               D0040PA01X+011300Y+149830               S0      
317ADM1276_SENSE+               D0040PA01X+011700Y+149830               S0      
317ADM1276_SENSE+               D0040PA01X+012100Y+149830               S0      
327ADM1276_SENSE+               D0040PA01X+011700Y+146160               S0      
317ADM1276_SENSE+   VIA        MD0040PA01X+010433Y+149817               S0      
327SENSE+_R4                    D0040PA01X+016525Y+161970               S0      
317SENSE+_R4                    D0040PA01X+010900Y+150170               S0      
317SENSE+_R4        VIA        MD0040PA04X+010450Y+150600               S0      
317SENSE+_R4        VIA        MD0040PA00X+010900Y+150650               S0      
317SENSE+_R4        VIA        MD0040PA00X+016988Y+162630               S0      
327SENSE+_R3                    D0040PA01X+013775Y+161970               S0      
317SENSE+_R3                    D0040PA01X+011300Y+150170               S0      
317SENSE+_R3        VIA        MD0040PA04X+010850Y+150150               S0      
317SENSE+_R3        VIA        MD0040PA00X+011300Y+150650               S0      
317SENSE+_R3        VIA        MD0040PA00X+014130Y+162500               S0      
327SENSE+_R2                    D0040PA01X+010925Y+161970               S0      
317SENSE+_R2                    D0040PA01X+011700Y+150170               S0      
317SENSE+_R2        VIA        MD0040PA04X+011450Y+150180               S0      
317SENSE+_R2        VIA        MD0040PA00X+011320Y+162280               S0      
317SENSE+_R2        VIA        MD0040PA00X+011700Y+150650               S0      
327SENSE+_R1                    D0040PA01X+007875Y+161970               S0      
317SENSE+_R1                    D0040PA01X+012100Y+150170               S0      
317SENSE+_R1        VIA        MD0040PA04X+011950Y+150100               S0      
317SENSE+_R1        VIA        MD0040PA00X+012100Y+150650               S0      
317SENSE+_R1        VIA        MD0040PA00X+008300Y+161970               S0      
317ADM1276_SENSE-               D0040PA01X+012500Y+149830               S0      
317ADM1276_SENSE-               D0040PA01X+012900Y+149830               S0      
317ADM1276_SENSE-               D0040PA01X+013300Y+149830               S0      
317ADM1276_SENSE-               D0040PA01X+013700Y+149830               S0      
327ADM1276_SENSE-               D0040PA01X+011956Y+146160               S0      
317ADM1276_SENSE-   VIA        MD0040PA01X+014240Y+149990               S0      
327SENSE-_R1                    D0040PA01X+007875Y+161330               S0      
317SENSE-_R1                    D0040PA01X+012500Y+150170               S0      
317SENSE-_R1        VIA        MD0040PA04X+012500Y+150050               S0      
317SENSE-_R1        VIA        MD0040PA00X+012500Y+150650               S0      
317SENSE-_R1        VIA        MD0040PA00X+008305Y+161600               S0      
327SENSE-_R2                    D0040PA01X+010925Y+161330               S0      
317SENSE-_R2                    D0040PA01X+012900Y+150170               S0      
317SENSE-_R2        VIA        MD0040PA04X+013000Y+150100               S0      
317SENSE-_R2        VIA        MD0040PA00X+011320Y+161930               S0      
317SENSE-_R2        VIA        MD0040PA00X+012900Y+150650               S0      
327SENSE-_R3                    D0040PA01X+013775Y+161330               S0      
317SENSE-_R3                    D0040PA01X+013300Y+150170               S0      
317SENSE-_R3        VIA        MD0040PA04X+013500Y+150050               S0      
317SENSE-_R3        VIA        MD0040PA00X+013300Y+150550               S0      
317SENSE-_R3        VIA        MD0040PA00X+014150Y+162160               S0      
327SENSE-_R4                    D0040PA01X+016525Y+161330               S0      
317SENSE-_R4                    D0040PA01X+013700Y+150170               S0      
317SENSE-_R4        VIA        MD0040PA04X+013850Y+150450               S0      
317SENSE-_R4        VIA        MD0040PA00X+013501Y+150825               S0      
317SENSE-_R4        VIA        MD0040PA00X+017327Y+162652               S0      
317ADM1276_PWRGD                D0040PA01X+014020Y+145330               S0      
327ADM1276_PWRGD                D0040PA01X+012660Y+144944               S0      
317ADM1276_PWRGD    VIA        MD0040PA01X+013300Y+144760               S0      
327TEMP_ALM#                    D0040PA01X+011380Y+139970               S0      
317TEMP_ALM#                    D0040PA01X+011530Y+140820               S0      
317TEMP_ALM#                    D0040PA01X+015450Y+068720               S0      
317TEMP_ALM#                    D0040PA01X+009247Y+060697               S0      
317TEMP_ALM#                    D0040PA01X+015573Y+061507               S0      
317TEMP_ALM#                    D0040PA01X+012934Y+066203               S0      
317TEMP_ALM#        VIA        MD0040PA04X+014600Y+064140               S0      
317TEMP_ALM#        VIA        MD0040PA00X+012870Y+140800               S0      
317TEMP_ALM#        VIA        MD0040PA00X+014265Y+066543               S0      
317TEMP_ALM#        VIA        MD0040PA00X+015098Y+068778               S0      
317TEMP_ALM#        VIA        MD0040PA00X+015270Y+061880               S0      
317TEMP_ALM#        VIA        MD0040PA00X+009063Y+060202               S0      
317D_LATCH_Q                    D0040PA01X+017180Y+070110               S0      
317D_LATCH_Q                    D0040PA01X+016770Y+069960               S0      
327D_LATCH_Q                    D0040PA01X+016606Y+071010               S0      
317D_LATCH_Q        VIA        MD0040PA01X+016760Y+070330               S0      
317P3V3_EN                      D0040PA01X+007080Y+098140               S0      
317P3V3_EN                      D0040PA01X+007660Y+098660               S0      
327P3V3_EN                      D0040PA01X+007740Y+098005               S0      
317P3V3_EN          VIA        MD0040PA01X+008150Y+098590               S0      
317P3V3_LX_REV                  D0040PA01X+009900Y+097630               S0      
317P3V3_LX_REV                  D0040PA01X+009400Y+096280               S0      
317P3V3_LX_REV      VIA        MD0040PA01X+009796Y+096696               S0      
317ADM1276_FLB                  D0040PA01X+014050Y+146240               S0      
317ADM1276_FLB                  D0040PA01X+014050Y+145840               S0      
327ADM1276_FLB                  D0040PA01X+012660Y+145200               S0      
317ADM1276_FLB      VIA        MD0040PA01X+013440Y+145430               S0      
317ADM1276_VOUT                 D0040PA01X+014050Y+146640               S0      
327ADM1276_VOUT                 D0040PA01X+012660Y+145456               S0      
317ADM1276_VOUT     VIA        MD0040PA01X+013610Y+146390               S0      
317NNAME00051                   D0040PA01X+012300Y+142420               S0      
327NNAME00051                   D0040PA01X+012212Y+144240               S0      
317NNAME00051       VIA        MD0040PA01X+012300Y+143130               S0      
317NNAME00052                   D0040PA01X+012750Y+142420               S0      
327NNAME00052                   D0040PA01X+012660Y+144688               S0      
317NNAME00052       VIA        MD0040PA01X+012698Y+143540               S0      
327TEMP_ALM#_G                  D0040PA01X+010640Y+139970               S0      
327TEMP_ALM#_G                  D0040PA01X+010640Y+139714               S0      
317TEMP_ALM#_G                  D0040PA01X+010410Y+140810               S0      
317TEMP_ALM#_G      VIA        MD0040PA01X+009950Y+140750               S0      
327LED_DR_LED5_B                D0040PA01X+002747Y+026255               S0      
317LED_DR_LED5_B                D0040PA01X+003268Y+026422               S0      
317LED_DR_LED5_B    VIA        MD0040PA01X+002790Y+026947               S0      
327LED_DR_LED4_B                D0040PA01X+002493Y+030535               S0      
317LED_DR_LED4_B                D0040PA01X+001928Y+030728               S0      
317LED_DR_LED4_B    VIA        MD0040PA01X+002001Y+030298               S0      
327LED_DR_LED3_B                D0040PA01X+005869Y+090987               S0      
317LED_DR_LED3_B                D0040PA01X+006410Y+090940               S0      
317LED_DR_LED3_B    VIA        MD0040PA01X+006410Y+090480               S0      
327LED_DR_LED2_B                D0040PA01X+003187Y+108921               S0      
317LED_DR_LED2_B                D0040PA01X+003800Y+109600               S0      
317LED_DR_LED2_B    VIA        MD0040PA01X+003720Y+109170               S0      
327LED_DR_LED1_B                D0040PA01X+003538Y+164905               S0      
317LED_DR_LED1_B                D0040PA01X+003290Y+166080               S0      
317LED_DR_LED1_B    VIA        MD0040PA01X+003290Y+165630               S0      
327LED_DR_LED0_B                D0040PA01X+002729Y+171487               S0      
317LED_DR_LED0_B                D0040PA01X+002180Y+172070               S0      
317LED_DR_LED0_B    VIA        MD0040PA01X+003300Y+171850               S0      
317NNAME00053                   D0040PA01X+014424Y+064993               S0      
327NNAME00053                   D0040PA01X+013624Y+064015               S0      
317NNAME00053       VIA        MD0040PA01X+014520Y+064460               S0      
317I2C_C_SDA                    D0040PA01X+013500Y+100320               S0      
317I2C_C_SDA                    D0040PA01X+014424Y+065333               S0      
317I2C_C_SDA                    D0040PA01X+012330Y+100130               S0      
317I2C_C_SDA                    D0040PA01X+012300Y+142080               S0      
317I2C_C_SDA                    D0040PA01X+005830Y+026330               S0      
317I2C_C_SDA        VIA        MD0040PA04X+005910Y+044109               S0      
317I2C_C_SDA        VIA        MD0040PA00X+013560Y+141620               S0      
317I2C_C_SDA        VIA        MD0040PA00X+006030Y+027570               S0      
317I2C_C_SDA        VIA        MD0040PA00X+014680Y+101890               S0      
317I2C_C_SDA        VIA        MD0040PA00X+015143Y+066174               S0      
317NNAME00054                   D0040PA01X+009727Y+059747               S0      
327NNAME00054                   D0040PA01X+010284Y+062047               S0      
317NNAME00054       VIA        MD0040PA01X+009958Y+060577               S0      
317FANIN_1                      D0040PA01X+002330Y+176960               S0      
327FANIN_1                      D0040PA01X+013036Y+064603               S0      
317FANIN_1                      D0040PA01X+002800Y+176990               S0      
317FANIN_1          VIA        MD0040PA04X+013750Y+068250               S0      
317FANIN_1          VIA        MD0040PA00X+013890Y+065010               S0      
317FANIN_1          VIA        MD0040PA00X+002500Y+176380               S0      
317FANIN_2                      D0040PA01X+004940Y+176980               S0      
327FANIN_2                      D0040PA01X+012840Y+064603               S0      
317FANIN_2                      D0040PA01X+005430Y+176470               S0      
317FANIN_2          VIA        MD0040PA04X+014180Y+067630               S0      
317FANIN_2          VIA        MD0040PA00X+013920Y+065390               S0      
317FANIN_2          VIA        MD0040PA00X+004530Y+177630               S0      
317FANIN_3                      D0040PA01X+006320Y+113860               S0      
327FANIN_3                      D0040PA01X+010284Y+063228               S0      
317FANIN_3                      D0040PA01X+006320Y+113395               S0      
317FANIN_3          VIA        MD0040PA04X+007900Y+067550               S0      
317FANIN_3          VIA        MD0040PA00X+006730Y+113349               S0      
317FANIN_3          VIA        MD0040PA00X+008090Y+066840               S0      
317FANIN_4                      D0040PA01X+007700Y+113790               S0      
327FANIN_4                      D0040PA01X+010284Y+063031               S0      
317FANIN_4                      D0040PA01X+008140Y+113775               S0      
317FANIN_4          VIA        MD0040PA04X+013211Y+067835               S0      
317FANIN_4          VIA        MD0040PA00X+013114Y+063955               S0      
317FANIN_4          VIA        MD0040PA00X+007829Y+114804               S0      
317NNAME00055                   D0040PA01X+013500Y+099980               S0      
327NNAME00055                   D0040PA01X+013990Y+098170               S0      
317NNAME00055       VIA        MD0040PA01X+013090Y+100340               S0      
317NNAME00056                   D0040PA01X+013910Y+099970               S0      
327NNAME00056                   D0040PA01X+014246Y+098170               S0      
317NNAME00056       VIA        MD0040PA01X+014310Y+100710               S0      
317I2C_C_SCL                    D0040PA01X+013910Y+100310               S0      
317I2C_C_SCL                    D0040PA01X+014843Y+065333               S0      
317I2C_C_SCL                    D0040PA01X+011930Y+100130               S0      
317I2C_C_SCL                    D0040PA01X+012750Y+142080               S0      
317I2C_C_SCL                    D0040PA01X+005430Y+026330               S0      
317I2C_C_SCL        VIA        MD0040PA04X+007617Y+055147               S0      
317I2C_C_SCL        VIA        MD0040PA00X+013450Y+142000               S0      
317I2C_C_SCL        VIA        MD0040PA00X+005750Y+026850               S0      
317I2C_C_SCL        VIA        MD0040PA00X+014390Y+102270               S0      
317I2C_C_SCL        VIA        MD0040PA00X+014899Y+065857               S0      
317NCT7904_ADR                  D0040PA01X+013354Y+065863               S0      
317NCT7904_ADR                  D0040PA01X+013777Y+065867               S0      
327NCT7904_ADR                  D0040PA01X+012643Y+064603               S0      
317NCT7904_ADR      VIA        MD0040PA01X+012900Y+065360               S0      
317NCT7904_RESET                D0040PA01X+009307Y+059747               S0      
327NCT7904_RESET                D0040PA01X+010284Y+062244               S0      
317NCT7904_RESET    VIA        MD0040PA01X+009455Y+060120               S0      
317NCT7904_VSEN7                D0040PA01X+012490Y+058860               S0      
317NCT7904_VSEN7                D0040PA01X+012890Y+058860               S0      
327NCT7904_VSEN7                D0040PA01X+012052Y+061263               S0      
317NCT7904_VSEN7    VIA        MD0040PA01X+012080Y+059870               S0      
317PWM_OUT_FAN6                 D0040PA01X+010290Y+083180               S0      
317PWM_OUT_FAN6                 D0040PA01X+008740Y+084410               S0      
327PWM_OUT_FAN6                 D0040PA01X+010338Y+084630               S0      
317PWM_OUT_FAN6     VIA        MD0040PA01X+010340Y+083830               S0      
317PWM_OUT_FAN5                 D0040PA01X+011120Y+083180               S0      
317PWM_OUT_FAN5                 D0040PA01X+008740Y+084850               S0      
327PWM_OUT_FAN5                 D0040PA01X+010850Y+084630               S0      
317PWM_OUT_FAN5     VIA        MD0040PA01X+009240Y+084890               S0      
317PWM_OUT_FAN4                 D0040PA01X+008740Y+085290               S0      
317PWM_OUT_FAN4                 D0040PA01X+011960Y+083180               S0      
327PWM_OUT_FAN4                 D0040PA01X+011362Y+084630               S0      
317PWM_OUT_FAN4     VIA        MD0040PA01X+011930Y+083700               S0      
317PWM_OUT_FAN3                 D0040PA01X+008740Y+085720               S0      
317PWM_OUT_FAN3                 D0040PA01X+011930Y+088140               S0      
327PWM_OUT_FAN3                 D0040PA01X+011617Y+086850               S0      
317PWM_OUT_FAN3     VIA        MD0040PA01X+009270Y+085810               S0      
317PWM_OUT_FAN2                 D0040PA01X+008740Y+086150               S0      
317PWM_OUT_FAN2                 D0040PA01X+011090Y+088140               S0      
327PWM_OUT_FAN2                 D0040PA01X+011106Y+086850               S0      
317PWM_OUT_FAN2     VIA        MD0040PA01X+011110Y+087670               S0      
317PWM_OUT_FAN1                 D0040PA01X+008740Y+086570               S0      
317PWM_OUT_FAN1                 D0040PA01X+010260Y+088140               S0      
327PWM_OUT_FAN1                 D0040PA01X+010594Y+086850               S0      
317PWM_OUT_FAN1     VIA        MD0040PA01X+009280Y+086530               S0      
317NNAME00057                   D0040PA01X+017430Y+062430               S0      
317NNAME00057                   D0040PA01X+016610Y+062670               S0      
317NNAME00057                   D0040PA01X+016610Y+062270               S0      
317NNAME00057                   D0040PA01X+017020Y+062710               S0      
317NNAME00057       VIA        MD0040PA01X+017902Y+062001               S0      
317NCT7904_VSEN6                D0040PA01X+012080Y+058860               S0      
317NCT7904_VSEN6                D0040PA01X+011680Y+058860               S0      
327NCT7904_VSEN6                D0040PA01X+011855Y+061263               S0      
317NCT7904_VSEN6    VIA        MD0040PA01X+011856Y+059285               S0      
317NCT7904D_PWM1                D0040PA01X+011630Y+066720               S0      
327NCT7904D_PWM1                D0040PA01X+012052Y+064603               S0      
317NCT7904D_PWM1    VIA        MD0040PA01X+012209Y+066591               S0      
317NNAME00058                   D0040PA01X+011630Y+067060               S0      
317NNAME00058                   D0040PA01X+011900Y+066020               S0      
317NNAME00058                   D0040PA01X+011630Y+067060               S0      
317NNAME00058                   D0040PA01X+005690Y+028000               S0      
327NNAME00058                   D0040PA01X+010850Y+086850               S0      
327NNAME00058                   D0040PA01X+010338Y+086850               S0      
317NNAME00058       VIA        MD0040PA04X+011522Y+076552               S0      
317NNAME00058       VIA        MD0040PA00X+010230Y+086344               S0      
317NNAME00058       VIA        MD0040PA00X+010716Y+086229               S0      
317NNAME00058       VIA        MD0040PA00X+011813Y+066340               S0      
317NNAME00058       VIA        MD0040PA00X+004580Y+027780               S0      
317NCT7904D_PWM2                D0040PA01X+011560Y+065680               S0      
327NCT7904D_PWM2                D0040PA01X+011658Y+064603               S0      
317NCT7904D_PWM2    VIA        MD0040PA01X+011930Y+065660               S0      
317NNAME00059                   D0040PA01X+011560Y+066020               S0      
317NNAME00059                   D0040PA01X+010830Y+066220               S0      
317NNAME00059                   D0040PA01X+011560Y+066020               S0      
317NNAME00059                   D0040PA01X+003620Y+027230               S0      
327NNAME00059                   D0040PA01X+011106Y+084630               S0      
327NNAME00059                   D0040PA01X+011362Y+086850               S0      
317NNAME00059       VIA        MD0040PA04X+011640Y+077940               S0      
317NNAME00059       VIA        MD0040PA00X+011150Y+085160               S0      
317NNAME00059       VIA        MD0040PA00X+011340Y+086220               S0      
317NNAME00059       VIA        MD0040PA00X+011400Y+066335               S0      
317NNAME00059       VIA        MD0040PA00X+004340Y+027230               S0      
317NCT7904D_PWM3                D0040PA01X+010490Y+065880               S0      
327NCT7904D_PWM3                D0040PA01X+011265Y+064603               S0      
317NCT7904D_PWM3    VIA        MD0040PA01X+011140Y+065850               S0      
317NNAME00060                   D0040PA01X+010490Y+066220               S0      
317NNAME00060                   D0040PA01X+010490Y+066220               S0      
317NNAME00060                   D0040PA01X+009520Y+066230               S0      
327NNAME00060                   D0040PA01X+010082Y+084630               S0      
327NNAME00060                   D0040PA01X+010594Y+084630               S0      
317NNAME00060       VIA        MD0040PA04X+011110Y+078820               S0      
317NNAME00060       VIA        MD0040PA00X+010030Y+084100               S0      
317NNAME00060       VIA        MD0040PA00X+010640Y+084070               S0      
317NNAME00060       VIA        MD0040PA00X+010901Y+066589               S0      
317PWM_OUT                      D0040PA01X+011290Y+067060               S0      
327PWM_OUT                      D0040PA01X+009321Y+068242               S0      
317PWM_OUT          VIA        MD0040PA01X+009870Y+087710               S0      
317PWM_OUT          VIA        MD0040PA00X+010020Y+066390               S0      
317PWM_OUT          VIA        MD0040PA00X+010150Y+087420               S0      
317PWM_OUT          VIA        MD0040PA00X+007240Y+082290               S0      
317PWM_OUT          VIA        MD0040PA00X+008660Y+068110               S0      
317PWM_OUT          VIA        MD0040PA00X+009890Y+082290               S0      
317THERMHOT#                    D0040PA01X+008340Y+068220               S0      
317THERMHOT#                    D0040PA01X+008410Y+068640               S0      
327THERMHOT#                    D0040PA01X+009321Y+068742               S0      
317THERMHOT#        VIA        MD0040PA01X+008600Y+068990               S0      
317THERMHOT#_R                  D0040PA01X+008000Y+068220               S0      
327THERMHOT#_R                  D0040PA01X+007200Y+068111               S0      
317THERMHOT#_R      VIA        MD0040PA04X+008048Y+068392               S0      
317THERMHOT#_R      VIA        MD0040PA00X+007610Y+068690               S0      
317THERMHOT#_R      VIA        MD0040PA00X+008385Y+067811               S0      
317NNAME00061                   D0040PA01X+014843Y+064993               S0      
327NNAME00061                   D0040PA01X+013624Y+063819               S0      
317NNAME00061       VIA        MD0040PA01X+015320Y+065320               S0      
317NCT7368S_SEL                 D0040PA01X+008196Y+069047               S0      
317NCT7368S_SEL                 D0040PA01X+008194Y+069464               S0      
327NCT7368S_SEL                 D0040PA01X+009321Y+069242               S0      
317NCT7368S_SEL     VIA        MD0040PA01X+008606Y+069520               S0      
317D_LATCH_CLR                  D0040PA01X+014950Y+071170               S0      
327D_LATCH_CLR                  D0040PA01X+015583Y+071010               S0      
317D_LATCH_CLR      VIA        MD0040PA01X+014500Y+071175               S0      
317FCB_EEPROM_A0                D0040PA01X+011050Y+093970               S0      
317FCB_EEPROM_A0                D0040PA01X+011253Y+095574               S0      
327FCB_EEPROM_A0                D0040PA01X+011396Y+096300               S0      
317FCB_EEPROM_A0    VIA        MD0040PA01X+010820Y+095350               S0      
317NCT7904_TMPALM               D0040PA01X+009247Y+061037               S0      
327NCT7904_TMPALM               D0040PA01X+010284Y+062637               S0      
317NCT7904_TMPALM   VIA        MD0040PA01X+009146Y+062314               S0      
317FCB_EEPROM_A1                D0040PA01X+011730Y+093970               S0      
317FCB_EEPROM_A1                D0040PA01X+011753Y+095574               S0      
327FCB_EEPROM_A1                D0040PA01X+011652Y+096300               S0      
317FCB_EEPROM_A1    VIA        MD0040PA01X+011298Y+094684               S0      
317FCB_EEPROM_A2                D0040PA01X+012167Y+093976               S0      
317FCB_EEPROM_A2                D0040PA01X+012253Y+095574               S0      
327FCB_EEPROM_A2                D0040PA01X+011908Y+096300               S0      
317FCB_EEPROM_A2    VIA        MD0040PA01X+012005Y+094560               S0      
317EEPROM_WP                    D0040PA01X+011480Y+099790               S0      
327EEPROM_WP                    D0040PA01X+011652Y+098520               S0      
317EEPROM_WP        VIA        MD0040PA01X+011040Y+099785               S0      
317NNAME00062                   D0040PA01X+011930Y+099790               S0      
327NNAME00062                   D0040PA01X+011908Y+098520               S0      
317NNAME00062       VIA        MD0040PA01X+011908Y+099290               S0      
317NNAME00063                   D0040PA01X+012330Y+099790               S0      
327NNAME00063                   D0040PA01X+012164Y+098520               S0      
317NNAME00063       VIA        MD0040PA01X+012770Y+099840               S0      
317LED_DRV_RST                  D0040PA01X+014380Y+099980               S0      
317LED_DRV_RST                  D0040PA01X+014200Y+099450               S0      
327LED_DRV_RST                  D0040PA01X+014502Y+098170               S0      
317NNAME00064                   D0040PA01X+005740Y+067340               S0      
327NNAME00064                   D0040PA01X+004275Y+068544               S0      
327NNAME00064                   D0040PA01X+006688Y+067461               S0      
317NNAME00064       VIA        MD0040PA01X+005720Y+066788               S0      
317NCT7904_CLKIN                D0040PA01X+015134Y+063243               S0      
327NCT7904_CLKIN                D0040PA01X+013624Y+063622               S0      
317NCT7904_CLKIN    VIA        MD0040PA01X+014666Y+063405               S0      
317NCT7904_VSEN1                D0040PA01X+016270Y+062270               S0      
327NCT7904_VSEN1                D0040PA01X+013624Y+063031               S0      
317NCT7904_VSEN1    VIA        MD0040PA01X+015720Y+062080               S0      
317NCT7904_VSEN9                D0040PA01X+017020Y+062370               S0      
327NCT7904_VSEN9                D0040PA01X+012446Y+061263               S0      
317NCT7904_VSEN9    VIA        MD0040PA04X+013650Y+059700               S0      
317NCT7904_VSEN9    VIA        MD0040PA00X+012900Y+059700               S0      
317NCT7904_VSEN9    VIA        MD0040PA00X+017035Y+061995               S0      
317NNAME00065                   D0040PA01X+006140Y+067340               S0      
327NNAME00065                   D0040PA01X+005825Y+068544               S0      
327NNAME00065                   D0040PA01X+006943Y+067461               S0      
317NNAME00065       VIA        MD0040PA04X+006050Y+067470               S0      
317NNAME00065       VIA        MD0040PA00X+006050Y+068254               S0      
317NNAME00065       VIA        MD0040PA00X+006090Y+067020               S0      
317LED_DRV_A0                   D0040PA01X+013150Y+094780               S0      
327LED_DRV_A0                   D0040PA01X+013734Y+095950               S0      
317LED_DRV_A0       VIA        MD0040PA01X+013090Y+095818               S0      
317LED_DRV_A1                   D0040PA01X+013600Y+094780               S0      
327LED_DRV_A1                   D0040PA01X+013990Y+095950               S0      
317LED_DRV_A1       VIA        MD0040PA01X+013350Y+095300               S0      
317LED_DRV_A2                   D0040PA01X+014050Y+094780               S0      
327LED_DRV_A2                   D0040PA01X+014246Y+095950               S0      
317LED_DRV_A2       VIA        MD0040PA01X+013950Y+095150               S0      
317NNAME00066                   D0040PA01X+015210Y+099980               S0      
317NNAME00066                   D0040PA01X+015400Y+099450               S0      
327NNAME00066                   D0040PA01X+015014Y+098170               S0      
317NNAME00067                   D0040PA01X+014790Y+099970               S0      
317NNAME00067                   D0040PA01X+014760Y+099460               S0      
327NNAME00067                   D0040PA01X+014758Y+098170               S0      
317NCT7904_SMI                  D0040PA01X+015233Y+061507               S0      
327NCT7904_SMI                  D0040PA01X+013624Y+062637               S0      
317NCT7904_SMI      VIA        MD0040PA01X+014860Y+061830               S0      
317NCT7904_RSTOUT               D0040PA01X+012934Y+065863               S0      
327NCT7904_RSTOUT               D0040PA01X+012446Y+064603               S0      
317NCT7904_RSTOUT   VIA        MD0040PA01X+012520Y+065750               S0      
317FANIN_10                     D0040PA01X+004960Y+057690               S0      
327FANIN_10                     D0040PA01X+011067Y+064603               S0      
317FANIN_10                     D0040PA01X+004510Y+057730               S0      
317FANIN_10         VIA        MD0040PA04X+010640Y+064830               S0      
317FANIN_10         VIA        MD0040PA00X+010820Y+065583               S0      
317FANIN_10         VIA        MD0040PA00X+005680Y+057695               S0      
317FANIN_12                     D0040PA01X+008580Y+007150               S0      
327FANIN_12                     D0040PA01X+011855Y+064603               S0      
317FANIN_12                     D0040PA01X+008130Y+007150               S0      
317FANIN_12         VIA        MD0040PA04X+005875Y+010115               S0      
317FANIN_12         VIA        MD0040PA00X+011740Y+065310               S0      
317FANIN_12         VIA        MD0040PA00X+008150Y+007550               S0      
317FANIN_9                      D0040PA01X+007840Y+059100               S0      
327FANIN_9                      D0040PA01X+011462Y+064603               S0      
317FANIN_9                      D0040PA01X+007350Y+059100               S0      
317FANIN_9          VIA        MD0040PA04X+008290Y+062060               S0      
317FANIN_9          VIA        MD0040PA00X+011280Y+065350               S0      
317FANIN_9          VIA        MD0040PA00X+007250Y+059590               S0      
317FANIN_11                     D0040PA01X+008830Y+006150               S0      
327FANIN_11                     D0040PA01X+012249Y+064603               S0      
317FANIN_11                     D0040PA01X+008385Y+006140               S0      
317FANIN_11         VIA        MD0040PA04X+007840Y+008610               S0      
317FANIN_11         VIA        MD0040PA00X+012250Y+065365               S0      
317FANIN_11         VIA        MD0040PA00X+008825Y+006550               S0      
327NCT7904_GND                  D0040PA01X+008944Y+063503               S0      
327NCT7904_GND                  D0040PA01X+010284Y+062834               S0      
317NCT7904_GND      VIA        MD0040PA01X+009306Y+062913               S0      
317FANIN_6                      D0040PA01X+006300Y+102060               S0      
327FANIN_6                      D0040PA01X+010284Y+063425               S0      
317FANIN_6                      D0040PA01X+006200Y+102500               S0      
317FANIN_6          VIA        MD0040PA04X+006700Y+090730               S0      
317FANIN_6          VIA        MD0040PA00X+005350Y+102550               S0      
317FANIN_6          VIA        MD0040PA00X+008450Y+066635               S0      
317FANIN_8                      D0040PA01X+007700Y+072740               S0      
327FANIN_8                      D0040PA01X+010284Y+063819               S0      
317FANIN_8                      D0040PA01X+008150Y+072760               S0      
317FANIN_8          VIA        MD0040PA04X+008390Y+065975               S0      
317FANIN_8          VIA        MD0040PA00X+007300Y+072800               S0      
317FANIN_8          VIA        MD0040PA00X+008897Y+065975               S0      
317FANIN_5                      D0040PA01X+006870Y+099980               S0      
327FANIN_5                      D0040PA01X+010284Y+063622               S0      
317FANIN_5                      D0040PA01X+006420Y+099850               S0      
317FANIN_5          VIA        MD0040PA04X+005420Y+092670               S0      
317FANIN_5          VIA        MD0040PA00X+005400Y+099650               S0      
317FANIN_5          VIA        MD0040PA00X+008644Y+066285               S0      
317FANIN_7                      D0040PA01X+007720Y+070250               S0      
327FANIN_7                      D0040PA01X+010284Y+064015               S0      
317FANIN_7                      D0040PA01X+008200Y+070260               S0      
317FANIN_7          VIA        MD0040PA04X+008400Y+067400               S0      
317FANIN_7          VIA        MD0040PA00X+007557Y+069250               S0      
317FANIN_7          VIA        MD0040PA00X+009067Y+066337               S0      
317NCT7904_VSEN11               D0040PA01X+013194Y+060193               S0      
327NCT7904_VSEN11               D0040PA01X+012840Y+061263               S0      
317NCT7904_VSEN12               D0040PA01X+014014Y+059323               S0      
327NCT7904_VSEN12               D0040PA01X+013036Y+061263               S0      
317NCT7904_PECI                 D0040PA01X+015670Y+062680               S0      
327NCT7904_PECI                 D0040PA01X+013624Y+063228               S0      
317NCT7904_VSEN13               D0040PA01X+013993Y+060417               S0      
327NCT7904_VSEN13               D0040PA01X+013624Y+061850               S0      
317NCT7904_VSEN14               D0040PA01X+014433Y+059876               S0      
327NCT7904_VSEN14               D0040PA01X+013624Y+062047               S0      
317NNAME00068                   D0040PA01X+015103Y+062757               S0      
327NNAME00068                   D0040PA01X+013624Y+063425               S0      
317NCT7904_LED                  D0040PA01X+009297Y+061734               S0      
327NCT7904_LED                  D0040PA01X+010284Y+062441               S0      
317NNAME00069                   D0040PA01X+016070Y+061590               S0      
327NNAME00069                   D0040PA01X+013624Y+062834               S0      
317D_LATCH_Q#                   D0040PA01X+017900Y+070650               S0      
327D_LATCH_Q#                   D0040PA01X+016862Y+071010               S0      
317NCT7904D_PWM4                D0040PA01X+010190Y+065410               S0      
327NCT7904D_PWM4                D0040PA01X+010871Y+064603               S0      
317NCT7904_VSEN8                D0040PA01X+012583Y+059363               S0      
327NCT7904_VSEN8                D0040PA01X+012249Y+061263               S0      
317NCT7904_VSEN10               D0040PA01X+013274Y+059343               S0      
327NCT7904_VSEN10               D0040PA01X+012643Y+061263               S0      
999
